G04 ================== begin FILE IDENTIFICATION RECORD ==================*
G04 Layout Name:  D:/<user>/Wistron_project/16318-2/gbr/16318-2.brd*
G04 Film Name:    L5VCC*
G04 File Format:  Gerber RS274X*
G04 File Origin:  Cadence Allegro 16.5-S056*
G04 Origin Date:  Mon Aug 07 11:09:45 2017*
G04 *
G04 Layer:  VIA CLASS/L5VCC*
G04 Layer:  PIN/L5VCC*
G04 Layer:  PACKAGE GEOMETRY/PWRVCC*
G04 Layer:  ETCH/L5VCC*
G04 Layer:  DRAWING FORMAT/LAYER_PCB_STORY*
G04 Layer:  DRAWING FORMAT/LAYER_L5VCC*
G04 *
G04 Offset:    (0.00 0.00)*
G04 Mirror:    No*
G04 Mode:      Negative*
G04 Rotation:  0*
G04 FullContactRelief:  No*
G04 UndefLineWidth:     6.00*
G04 ================== end FILE IDENTIFICATION RECORD ====================*
%FSLAX35Y35*MOIN*%
%IR0*IPPOS*OFA0.00000B0.00000*MIA0B0*SFA1.00000B1.00000*%
%ADD27O,.072X.123*%
%ADD14C,.03*%
%ADD21C,.032*%
%ADD38C,.051*%
%ADD26C,.06*%
%ADD33C,.043*%
%ADD30C,.062*%
%ADD36C,.063*%
%ADD11C,.036*%
%ADD23C,.028*%
%ADD31C,.056*%
%ADD29C,.076*%
%ADD12C,.068*%
%AMMACRO18*
4,1,15,.00398,.00044,
.003999,.000208,
.004004,-.000025,
.003996,-.000258,
.00398,-.00044,
.00483,-.00129,
.004897,-.001007,
.004947,-.000721,
.004981,-.000432,
.004997,-.000141,
.004997,.000149,
.00498,.00044,
.004946,.000729,
.004895,.001015,
.00483,.00129,
.00398,.00044,
90.*
4,1,15,.00044,-.00398,
.000208,-.003999,
-.000025,-.004004,
-.000258,-.003996,
-.00044,-.00398,
-.00129,-.00483,
-.001007,-.004897,
-.000721,-.004947,
-.000432,-.004981,
-.000141,-.004997,
.000149,-.004997,
.00044,-.00498,
.000729,-.004946,
.001015,-.004895,
.00129,-.00483,
.00044,-.00398,
90.*
4,1,15,-.00398,-.00044,
-.003999,-.000208,
-.004004,.000025,
-.003996,.000258,
-.00398,.00044,
-.00483,.00129,
-.004897,.001007,
-.004947,.000721,
-.004981,.000432,
-.004997,.000141,
-.004997,-.000149,
-.00498,-.00044,
-.004946,-.000729,
-.004895,-.001015,
-.00483,-.00129,
-.00398,-.00044,
90.*
4,1,15,-.00044,.00398,
-.000208,.003999,
.000025,.004004,
.000258,.003996,
.00044,.00398,
.00129,.00483,
.001007,.004897,
.000721,.004947,
.000432,.004981,
.000141,.004997,
-.000149,.004997,
-.00044,.00498,
-.000729,.004946,
-.001015,.004895,
-.00129,.00483,
-.00044,.00398,
90.*
%
%ADD18MACRO18*%
%AMMACRO24*
4,1,15,-.00398,.00044,
-.003999,.000208,
-.004004,-.000025,
-.003996,-.000258,
-.00398,-.00044,
-.00483,-.00129,
-.004897,-.001007,
-.004947,-.000721,
-.004981,-.000432,
-.004997,-.000141,
-.004997,.000149,
-.00498,.00044,
-.004946,.000729,
-.004895,.001015,
-.00483,.00129,
-.00398,.00044,
90.*
4,1,15,-.00044,-.00398,
-.000208,-.003999,
.000025,-.004004,
.000258,-.003996,
.00044,-.00398,
.00129,-.00483,
.001007,-.004897,
.000721,-.004947,
.000432,-.004981,
.000141,-.004997,
-.000149,-.004997,
-.00044,-.00498,
-.000729,-.004946,
-.001015,-.004895,
-.00129,-.00483,
-.00044,-.00398,
90.*
4,1,15,.00398,-.00044,
.003999,-.000208,
.004004,.000025,
.003996,.000258,
.00398,.00044,
.00483,.00129,
.004897,.001007,
.004947,.000721,
.004981,.000432,
.004997,.000141,
.004997,-.000149,
.00498,-.00044,
.004946,-.000729,
.004895,-.001015,
.00483,-.00129,
.00398,-.00044,
90.*
4,1,15,.00044,.00398,
.000208,.003999,
-.000025,.004004,
-.000258,.003996,
-.00044,.00398,
-.00129,.00483,
-.001007,.004897,
-.000721,.004947,
-.000432,.004981,
-.000141,.004997,
.000149,.004997,
.00044,.00498,
.000729,.004946,
.001015,.004895,
.00129,.00483,
.00044,.00398,
90.*
%
%ADD24MACRO24*%
%AMMACRO10*
4,1,15,.00398,.00044,
.003999,.000208,
.004004,-.000025,
.003996,-.000258,
.00398,-.00044,
.00483,-.00129,
.004897,-.001007,
.004947,-.000721,
.004981,-.000432,
.004997,-.000141,
.004997,.000149,
.00498,.00044,
.004946,.000729,
.004895,.001015,
.00483,.00129,
.00398,.00044,
0.0*
4,1,15,.00044,-.00398,
.000208,-.003999,
-.000025,-.004004,
-.000258,-.003996,
-.00044,-.00398,
-.00129,-.00483,
-.001007,-.004897,
-.000721,-.004947,
-.000432,-.004981,
-.000141,-.004997,
.000149,-.004997,
.00044,-.00498,
.000729,-.004946,
.001015,-.004895,
.00129,-.00483,
.00044,-.00398,
0.0*
4,1,15,-.00398,-.00044,
-.003999,-.000208,
-.004004,.000025,
-.003996,.000258,
-.00398,.00044,
-.00483,.00129,
-.004897,.001007,
-.004947,.000721,
-.004981,.000432,
-.004997,.000141,
-.004997,-.000149,
-.00498,-.00044,
-.004946,-.000729,
-.004895,-.001015,
-.00483,-.00129,
-.00398,-.00044,
0.0*
4,1,15,-.00044,.00398,
-.000208,.003999,
.000025,.004004,
.000258,.003996,
.00044,.00398,
.00129,.00483,
.001007,.004897,
.000721,.004947,
.000432,.004981,
.000141,.004997,
-.000149,.004997,
-.00044,.00498,
-.000729,.004946,
-.001015,.004895,
-.00129,.00483,
-.00044,.00398,
0.0*
%
%ADD10MACRO10*%
%ADD35C,.122*%
%ADD13C,.114*%
%ADD34C,.125*%
%ADD37C,.127*%
%ADD25C,.208*%
%ADD16O,.296X.162*%
%ADD39C,.147*%
%ADD28O,.072X.096*%
%ADD22C,.158*%
%ADD15C,.178*%
%ADD20C,.198*%
%AMMACRO40*
4,1,15,.00398,.00044,
.003999,.000208,
.004004,-.000025,
.003996,-.000258,
.00398,-.00044,
.00483,-.00129,
.004897,-.001007,
.004947,-.000721,
.004981,-.000432,
.004997,-.000141,
.004997,.000149,
.00498,.00044,
.004946,.000729,
.004895,.001015,
.00483,.00129,
.00398,.00044,
135.*
4,1,15,.00044,-.00398,
.000208,-.003999,
-.000025,-.004004,
-.000258,-.003996,
-.00044,-.00398,
-.00129,-.00483,
-.001007,-.004897,
-.000721,-.004947,
-.000432,-.004981,
-.000141,-.004997,
.000149,-.004997,
.00044,-.00498,
.000729,-.004946,
.001015,-.004895,
.00129,-.00483,
.00044,-.00398,
135.*
4,1,15,-.00398,-.00044,
-.003999,-.000208,
-.004004,.000025,
-.003996,.000258,
-.00398,.00044,
-.00483,.00129,
-.004897,.001007,
-.004947,.000721,
-.004981,.000432,
-.004997,.000141,
-.004997,-.000149,
-.00498,-.00044,
-.004946,-.000729,
-.004895,-.001015,
-.00483,-.00129,
-.00398,-.00044,
135.*
4,1,15,-.00044,.00398,
-.000208,.003999,
.000025,.004004,
.000258,.003996,
.00044,.00398,
.00129,.00483,
.001007,.004897,
.000721,.004947,
.000432,.004981,
.000141,.004997,
-.000149,.004997,
-.00044,.00498,
-.000729,.004946,
-.001015,.004895,
-.00129,.00483,
-.00044,.00398,
135.*
%
%ADD40MACRO40*%
%AMMACRO19*
4,1,15,.00398,.00044,
.003999,.000208,
.004004,-.000025,
.003996,-.000258,
.00398,-.00044,
.00483,-.00129,
.004897,-.001007,
.004947,-.000721,
.004981,-.000432,
.004997,-.000141,
.004997,.000149,
.00498,.00044,
.004946,.000729,
.004895,.001015,
.00483,.00129,
.00398,.00044,
270.*
4,1,15,.00044,-.00398,
.000208,-.003999,
-.000025,-.004004,
-.000258,-.003996,
-.00044,-.00398,
-.00129,-.00483,
-.001007,-.004897,
-.000721,-.004947,
-.000432,-.004981,
-.000141,-.004997,
.000149,-.004997,
.00044,-.00498,
.000729,-.004946,
.001015,-.004895,
.00129,-.00483,
.00044,-.00398,
270.*
4,1,15,-.00398,-.00044,
-.003999,-.000208,
-.004004,.000025,
-.003996,.000258,
-.00398,.00044,
-.00483,.00129,
-.004897,.001007,
-.004947,.000721,
-.004981,.000432,
-.004997,.000141,
-.004997,-.000149,
-.00498,-.00044,
-.004946,-.000729,
-.004895,-.001015,
-.00483,-.00129,
-.00398,-.00044,
270.*
4,1,15,-.00044,.00398,
-.000208,.003999,
.000025,.004004,
.000258,.003996,
.00044,.00398,
.00129,.00483,
.001007,.004897,
.000721,.004947,
.000432,.004981,
.000141,.004997,
-.000149,.004997,
-.00044,.00498,
-.000729,.004946,
-.001015,.004895,
-.00129,.00483,
-.00044,.00398,
270.*
%
%ADD19MACRO19*%
%AMMACRO17*
4,1,15,.00398,.00044,
.003999,.000208,
.004004,-.000025,
.003996,-.000258,
.00398,-.00044,
.00483,-.00129,
.004897,-.001007,
.004947,-.000721,
.004981,-.000432,
.004997,-.000141,
.004997,.000149,
.00498,.00044,
.004946,.000729,
.004895,.001015,
.00483,.00129,
.00398,.00044,
180.*
4,1,15,.00044,-.00398,
.000208,-.003999,
-.000025,-.004004,
-.000258,-.003996,
-.00044,-.00398,
-.00129,-.00483,
-.001007,-.004897,
-.000721,-.004947,
-.000432,-.004981,
-.000141,-.004997,
.000149,-.004997,
.00044,-.00498,
.000729,-.004946,
.001015,-.004895,
.00129,-.00483,
.00044,-.00398,
180.*
4,1,15,-.00398,-.00044,
-.003999,-.000208,
-.004004,.000025,
-.003996,.000258,
-.00398,.00044,
-.00483,.00129,
-.004897,.001007,
-.004947,.000721,
-.004981,.000432,
-.004997,.000141,
-.004997,-.000149,
-.00498,-.00044,
-.004946,-.000729,
-.004895,-.001015,
-.00483,-.00129,
-.00398,-.00044,
180.*
4,1,15,-.00044,.00398,
-.000208,.003999,
.000025,.004004,
.000258,.003996,
.00044,.00398,
.00129,.00483,
.001007,.004897,
.000721,.004947,
.000432,.004981,
.000141,.004997,
-.000149,.004997,
-.00044,.00498,
-.000729,.004946,
-.001015,.004895,
-.00129,.00483,
-.00044,.00398,
180.*
%
%ADD17MACRO17*%
%AMMACRO32*
4,1,19,.02172,.00757,
.022123,.006294,
.022452,.004997,
.022705,.003683,
.02288,.002357,
.022979,.001023,
.022999,-.000315,
.022942,-.001652,
.022807,-.002983,
.022595,-.004304,
.022307,-.005611,
.021943,-.006898,
.02172,-.00757,
.02556,-.01142,
.027155,-.006808,
.027924,-.001989,
.027846,.00289,
.026921,.007681,
.02556,.01142,
.02172,.00757,
0.0*
4,1,19,.00757,-.02172,
.006294,-.022123,
.004997,-.022452,
.003683,-.022705,
.002357,-.02288,
.001023,-.022979,
-.000315,-.022999,
-.001652,-.022942,
-.002983,-.022807,
-.004304,-.022595,
-.005611,-.022307,
-.006898,-.021943,
-.00757,-.02172,
-.01142,-.02556,
-.006808,-.027155,
-.001989,-.027924,
.00289,-.027846,
.007681,-.026921,
.01142,-.02556,
.00757,-.02172,
0.0*
4,1,19,-.02172,-.00757,
-.022123,-.006294,
-.022452,-.004997,
-.022705,-.003683,
-.02288,-.002357,
-.022979,-.001023,
-.022999,.000315,
-.022942,.001652,
-.022807,.002983,
-.022595,.004304,
-.022307,.005611,
-.021943,.006898,
-.02172,.00757,
-.02556,.01142,
-.027155,.006808,
-.027924,.001989,
-.027846,-.00289,
-.026921,-.007681,
-.02556,-.01142,
-.02172,-.00757,
0.0*
4,1,19,-.00757,.02172,
-.006294,.022123,
-.004997,.022452,
-.003683,.022705,
-.002357,.02288,
-.001023,.022979,
.000315,.022999,
.001652,.022942,
.002983,.022807,
.004304,.022595,
.005611,.022307,
.006898,.021943,
.00757,.02172,
.01142,.02556,
.006808,.027155,
.001989,.027924,
-.00289,.027846,
-.007681,.026921,
-.01142,.02556,
-.00757,.02172,
0.0*
%
%ADD32MACRO32*%
%ADD41C,.02*%
%ADD42C,.006*%
%ADD47C,.08004*%
%ADD49C,.07204*%
%ADD52C,.05604*%
%ADD50C,.05804*%
%ADD44C,.11004*%
%ADD53C,.12104*%
%ADD54C,.11804*%
%ADD46C,.15404*%
%ADD48O,.29202X.15802*%
%ADD55C,.23626*%
%ADD43O,.29204X.15804*%
%ADD57C,.2369*%
%ADD45C,.37406*%
%ADD51C,.2964*%
%ADD56C,.37566*%
G75*
%LPD*%
G75*
G36*
G01X-6000Y-6000D02*
X931197D01*
Y769780D01*
X-6000D01*
Y-6000D01*
G37*
%LPC*%
G75*
G36*
G01X5000Y425721D02*
X5915Y426636D01*
G02X6504Y426609I282J-283D01*
G03X10937Y427367I1996J1670D01*
G01X115197D01*
Y5000D01*
X5000D01*
Y425721D01*
G37*
G36*
G01X73373Y503052D02*
X73330Y502932D01*
G03X76152Y500110I2069J-753D01*
G01X76272Y500153D01*
X103779Y472646D01*
X144086D01*
X144107Y472470D01*
G03X148479I2186J268D01*
G01X148500Y472646D01*
X173964D01*
X174009Y472509D01*
G03X178191I2091J691D01*
G01X178236Y472646D01*
X210906D01*
X210938Y472484D01*
G03X215262I2162J416D01*
G01X215294Y472646D01*
X274012D01*
G03X276388I1188J1854D01*
G01X281215D01*
G03X283456Y472566I1188J1854D01*
G01X306872Y449150D01*
X328785D01*
X348750Y429185D01*
Y400489D01*
X344304Y396043D01*
X344247Y396030D01*
G03X342584Y394367I485J-2148D01*
G01X342571Y394310D01*
X332820Y384559D01*
G03X332141Y383880I1180J-1859D01*
G01X330317Y382056D01*
Y36880D01*
X346712Y20485D01*
X353808D01*
G03X355788I990J1967D01*
G01X415244D01*
X438309Y43550D01*
X507628D01*
X510135Y46057D01*
X531078D01*
X539571Y54550D01*
X555911D01*
X559911Y58550D01*
X595779D01*
X595818Y58400D01*
G03X600082I2132J550D01*
G01X600121Y58550D01*
X613400D01*
X622954Y48996D01*
X768445D01*
X794322Y74873D01*
X816210D01*
X832076Y59007D01*
Y10974D01*
X831949Y10924D01*
G03X831180Y6543I946J-2424D01*
G02X831199Y5960I-264J-300D01*
G01X830239Y5000D01*
X292520D01*
Y429331D01*
G03X283583Y438268I-8937J0D01*
G01X124134D01*
G03X115197Y429331I0J-8937D01*
G01Y428867D01*
X11039D01*
X10997Y429011D01*
G03X6436Y429863I-2497J-732D01*
G02X5835Y429824I-318J243D01*
G01X5000Y430659D01*
Y716911D01*
X6666Y718577D01*
X20047D01*
X20048Y718576D01*
X53318D01*
X58672Y723930D01*
X58695Y723943D01*
G03X64442Y729163I-9482J16213D01*
G01X95776D01*
X97267Y727672D01*
Y701647D01*
X92007Y696387D01*
X69868D01*
X55021Y681540D01*
Y521404D01*
X73373Y503052D01*
G37*
G36*
G01X10381Y720077D02*
G03X6821Y720267I-1881J-1798D01*
G01X6681Y720148D01*
X5000Y721829D01*
Y723229D01*
X22776Y758780D01*
X43222D01*
G02X43347Y758000I0J-400D01*
G03X53428Y721854I5866J-17843D01*
G02X53801Y721181I90J-390D01*
G01X52696Y720076D01*
X20670D01*
X20669Y720077D01*
X10381D01*
G37*
G36*
G01X835261Y5000D02*
X834432Y5829D01*
G02X834472Y6430I282J283D01*
G03X833713Y10970I-1577J2070D01*
G01X833576Y11015D01*
Y59629D01*
X816832Y76373D01*
X793700D01*
X767823Y50496D01*
X623576D01*
X614022Y60050D01*
X599858D01*
G03X596042I-1908J-1100D01*
G01X559289D01*
X555289Y56050D01*
X538949D01*
X530456Y47557D01*
X509513D01*
X507006Y45050D01*
X437687D01*
X422550Y29913D01*
G02X421917Y30388I-282J283D01*
G03X396954Y22741I-16404J8982D01*
G02X396771Y21985I-183J-356D01*
G01X347334D01*
X331817Y37502D01*
Y381434D01*
X350250Y399867D01*
Y429807D01*
X344903Y435154D01*
X344902Y435235D01*
G03X342735Y437402I-2202J-35D01*
G01X342654Y437403D01*
X329407Y450650D01*
X307494D01*
X283998Y474146D01*
X214916D01*
G03X211284I-1816J-1246D01*
G01X178088D01*
G03X174112I-1988J-946D01*
G01X147986D01*
G03X144600I-1693J-1408D01*
G01X104401D01*
X77366Y501181D01*
X77420Y501305D01*
G03X74525Y504200I-2021J874D01*
G01X74401Y504146D01*
X56521Y522026D01*
Y651390D01*
X58266Y653135D01*
X108854D01*
X110484Y651505D01*
Y605602D01*
X115090Y600996D01*
X115104Y600969D01*
G03X116019Y600054I1946J1031D01*
G01X116046Y600040D01*
X125784Y590302D01*
X143474D01*
X143529Y590190D01*
G03X146223I1347J664D01*
G01X146278Y590302D01*
X170251D01*
G02X170650Y589871I0J-400D01*
G03X172981Y588718I1398J-107D01*
G01X175080Y586619D01*
Y582679D01*
X174401Y582000D01*
X171751D01*
X168751Y579000D01*
X153727D01*
X150813Y576086D01*
X150601D01*
X104648Y530133D01*
X70922D01*
X67200Y533855D01*
Y551011D01*
X65443Y552768D01*
X60869D01*
X59140Y551039D01*
Y535427D01*
X69018Y525549D01*
X106622D01*
X150542Y569469D01*
X151882D01*
X152751Y568600D01*
X174751D01*
X175080Y568271D01*
Y560100D01*
X174405Y559425D01*
X174391Y559415D01*
G03X174050Y559074I806J-1147D01*
G01X174040Y559060D01*
X172406Y557426D01*
X147574D01*
X144274Y554126D01*
Y534465D01*
X147741Y530998D01*
X147748Y530928D01*
G03X149090Y529586I1494J152D01*
G01X149160Y529579D01*
X159026Y519713D01*
G03X159553Y519490I538J537D01*
G03X159563I5J750D01*
G01X284037D01*
G03X284574Y519713I-1J760D01*
G01X293234Y528373D01*
X293305Y528380D01*
G03X295278Y530353I-218J2191D01*
G01X295285Y530424D01*
X311050Y546189D01*
Y604411D01*
X306311Y609150D01*
X301223D01*
X288813Y621560D01*
X288840Y621669D01*
G03X286179Y624330I-2140J521D01*
G01X286070Y624303D01*
X276621Y633752D01*
X276699Y633885D01*
G03X273685Y636899I-1899J1115D01*
G01X273552Y636821D01*
X257111Y653262D01*
X219375D01*
G03X217025I-1175J-1862D01*
G01X135569D01*
X134946Y653885D01*
X135304Y654243D01*
X135421Y654205D01*
G03X136564Y658453I679J2095D01*
G01X136406Y658487D01*
Y667945D01*
X211411Y742950D01*
X269389D01*
X284550Y727789D01*
Y664689D01*
X301489Y647750D01*
X315574D01*
X317250Y646074D01*
Y626689D01*
X319689Y624250D01*
X340389D01*
X350950Y613689D01*
Y608489D01*
X368689Y590750D01*
X392411D01*
X396850Y595189D01*
Y677543D01*
X396997Y677583D01*
G03X398057Y681180I-578J2125D01*
G02Y681714I297J267D01*
G03X397975Y684744I-1638J1472D01*
G02Y685028I141J142D01*
G03X396997Y688711I-1556J1558D01*
G01X396850Y688751D01*
Y690533D01*
X396976Y690583D01*
G03Y694677I-810J2047D01*
G01X396850Y694727D01*
Y713111D01*
X394511Y715450D01*
X353811D01*
X350511Y718750D01*
X346489D01*
X343189Y715450D01*
X335146D01*
X333550Y717046D01*
Y757189D01*
X335141Y758780D01*
X358444D01*
G02X358564Y757998I0J-400D01*
G03X369782I5609J-17841D01*
G02X369902Y758780I120J382D01*
G01X385492D01*
X403268Y723229D01*
Y188976D01*
G03X415090Y183976I6969J0D01*
G01X561288D01*
G03X573110Y188975I4853J5000D01*
G01Y354414D01*
X573846Y355150D01*
X591711D01*
X594111Y357550D01*
X650404D01*
X667938Y375084D01*
X680045D01*
X723050Y418089D01*
Y470989D01*
X727611Y475550D01*
X784811D01*
X792050Y482789D01*
Y507389D01*
X819711Y535050D01*
X819811D01*
X825450Y540689D01*
Y592911D01*
X822411Y595950D01*
X816911D01*
X814811Y598050D01*
X772389D01*
X718689Y544350D01*
X688789D01*
X670050Y525611D01*
Y464411D01*
X629231Y423592D01*
G02X628598Y424067I-282J283D01*
G03X604984Y415819I-16392J9004D01*
G02X604829Y415050I-155J-369D01*
G01X578635D01*
G03X574643Y415119I-2025J-1634D01*
G01X574583Y415050D01*
X574046D01*
X573110Y415986D01*
Y723229D01*
X590886Y758780D01*
X606476D01*
G02X606596Y757998I0J-400D01*
G03X617814I5609J-17841D01*
G02X617934Y758780I120J382D01*
G01X870255D01*
G02X870375Y757998I0J-400D01*
G03X881593I5609J-17841D01*
G02X881713Y758780I120J382D01*
G01X902421D01*
X920197Y723229D01*
Y5000D01*
X835261D01*
G37*
G36*
G01X175080Y578659D02*
X174932Y578619D01*
G03Y575913I366J-1353D01*
G01X175080Y575873D01*
Y570129D01*
X174751Y569800D01*
X153249D01*
X152380Y570669D01*
X150542D01*
X150392Y570819D01*
X149770D01*
X106000Y527049D01*
X69640D01*
X60640Y536049D01*
Y550417D01*
X61491Y551268D01*
X64821D01*
X65700Y550389D01*
Y533233D01*
X70300Y528633D01*
X105270D01*
X151662Y575025D01*
Y575237D01*
X154225Y577800D01*
X169249D01*
X172249Y580800D01*
X174451D01*
X175080Y580171D01*
Y578659D01*
G37*
G36*
G01X137904Y752943D02*
X138029Y752890D01*
G03X141391Y756430I1028J2390D01*
G01X143741Y758780D01*
X330459D01*
X332050Y757189D01*
Y756937D01*
X332008Y756883D01*
G03X332050Y753624I2049J-1603D01*
G01Y689798D01*
G03Y689602I2600J-98D01*
G01Y652811D01*
X328489Y649250D01*
X327437D01*
X327392Y649388D01*
G03X323208I-2092J-688D01*
G01X323163Y649250D01*
X302111D01*
X286050Y665311D01*
Y728411D01*
X270011Y744450D01*
X210789D01*
X134906Y668567D01*
Y658150D01*
G03X134110Y655358I1194J-1850D01*
G01X134170Y655231D01*
X133574Y654635D01*
X109476D01*
X109461Y654650D01*
X108839D01*
X108824Y654635D01*
X58426D01*
X56521Y656540D01*
Y680918D01*
X70490Y694887D01*
X92629D01*
X98767Y701025D01*
Y727906D01*
X100024Y729163D01*
X113772D01*
G03X113775I1J750D01*
G03X114372Y729411I-3J850D01*
G01X137904Y752943D01*
G37*
G36*
G01X140370Y757531D02*
X140241Y757597D01*
G03X136740Y754096I-1184J-2317D01*
G01X136806Y753967D01*
X113502Y730663D01*
X66103D01*
G02X65751Y731253I0J400D01*
G03X55079Y758000I-16538J8904D01*
G02X55204Y758780I125J380D01*
G01X140653D01*
G02X140936Y758097I0J-400D01*
G01X140370Y757531D01*
G37*
G36*
G01X176580Y559478D02*
Y576697D01*
X176595Y576734D01*
G03Y577798I-1297J532D01*
G01X176580Y577835D01*
Y587241D01*
X172238Y591582D01*
Y591583D01*
X172019Y591802D01*
X146041D01*
G03X143711I-1165J-948D01*
G01X126406D01*
X111984Y606224D01*
Y651523D01*
X113596Y653135D01*
X133574D01*
X134947Y651762D01*
X256489D01*
X272673Y635578D01*
X272649Y635472D01*
G03X275272Y632849I2151J-472D01*
G01X275378Y632873D01*
X284853Y623398D01*
X284779Y623266D01*
G03X287776Y620269I1921J-1076D01*
G01X287908Y620343D01*
X300601Y607650D01*
X305689D01*
X309550Y603789D01*
Y546811D01*
X283729Y520990D01*
X159871D01*
X150544Y530317D01*
X150603Y530444D01*
G03X148606Y532441I-1361J636D01*
G01X148479Y532382D01*
X145774Y535087D01*
Y553504D01*
X148196Y555926D01*
X173028D01*
X174289Y557187D01*
X174425Y557097D01*
G03X176368Y559040I772J1171D01*
G01X176278Y559176D01*
X176580Y559478D01*
G37*
G36*
G01X395350Y677783D02*
Y595811D01*
X391789Y592250D01*
X369311D01*
X352450Y609111D01*
Y614311D01*
X341011Y625750D01*
X320311D01*
X318750Y627311D01*
Y646074D01*
X320426Y647750D01*
X323313D01*
G03X327287I1987J950D01*
G01X329111D01*
X330098Y648737D01*
X330125Y648751D01*
G03X331063Y649702I-1025J1949D01*
G01X333550Y652189D01*
Y654610D01*
G03Y657054I-1832J1222D01*
G01Y712354D01*
X335146Y713950D01*
X343811D01*
X347111Y717250D01*
X349889D01*
X353189Y713950D01*
X387071D01*
G03X390181I1555J1559D01*
G01X393889D01*
X395350Y712489D01*
Y694675D01*
G03Y690585I816J-2045D01*
G01Y688511D01*
G03X394863Y685028I1069J-1925D01*
G02Y684744I-141J-142D01*
G03X394781Y681714I1556J-1558D01*
G02Y681180I-297J-267D01*
G03X395350Y677783I1638J-1472D01*
G37*
G36*
G01X819089Y536550D02*
X796853Y514314D01*
X796799Y514301D01*
G03X795184Y512686I524J-2139D01*
G01X795171Y512632D01*
X790550Y508011D01*
Y483411D01*
X784189Y477050D01*
X726989D01*
X721550Y471611D01*
Y418711D01*
X679423Y376584D01*
X667316D01*
X649782Y359050D01*
X593489D01*
X591089Y356650D01*
X574446D01*
X573110Y357986D01*
Y412414D01*
X574246Y413550D01*
X621311D01*
X671550Y463789D01*
Y524989D01*
X689411Y542850D01*
X719311D01*
X773011Y596550D01*
X814189D01*
X816289Y594450D01*
X821789D01*
X823950Y592289D01*
Y541311D01*
X819189Y536550D01*
X819089D01*
G37*
%LPD*%
G75*
G36*
G01X305778Y340592D02*
G02X302756I-1511J0D01*
G01Y344093D01*
G02X305778Y344092I1511J-1D01*
G01Y340592D01*
G37*
G36*
G01X309078Y353192D02*
G02X306056I-1511J0D01*
G01Y356693D01*
G02X309078Y356692I1511J-1D01*
G01Y353192D01*
G37*
G36*
G01X305778Y365792D02*
G02X302756I-1511J0D01*
G01Y369293D01*
G02X305778Y369292I1511J-1D01*
G01Y365792D01*
G37*
G36*
G01X326670Y350371D02*
G02X329694I1512J0D01*
G01Y346870D01*
G02X326670Y346871I-1512J1D01*
G01Y350371D01*
G37*
G36*
G01X329694Y372018D02*
G02X326670I-1512J0D01*
G01Y375519D01*
G02X329694Y375518I1512J-1D01*
G01Y372018D01*
G37*
G36*
G01X305778Y315392D02*
G02X302756I-1511J0D01*
G01Y318893D01*
G02X305778Y318892I1511J-1D01*
G01Y315392D01*
G37*
G36*
G01X309078Y277592D02*
G02X306056I-1511J0D01*
G01Y281093D01*
G02X309078Y281092I1511J-1D01*
G01Y277592D01*
G37*
G36*
G01X305778Y290192D02*
G02X302756I-1511J0D01*
G01Y293693D01*
G02X305778Y293692I1511J-1D01*
G01Y290192D01*
G37*
G36*
G01X309078Y302792D02*
G02X306056I-1511J0D01*
G01Y306293D01*
G02X309078Y306292I1511J-1D01*
G01Y302792D01*
G37*
G36*
G01X329694Y296477D02*
G02X326670I-1512J0D01*
G01Y299978D01*
G02X329694Y299977I1512J-1D01*
G01Y296477D01*
G37*
G36*
G01Y321674D02*
G02X326670I-1512J0D01*
G01Y325175D01*
G02X329694Y325174I1512J-1D01*
G01Y321674D01*
G37*
G36*
G01X309078Y328092D02*
G02X306056I-1511J0D01*
G01Y331593D01*
G02X309078Y331592I1511J-1D01*
G01Y328092D01*
G37*
G36*
G01X302720Y268548D02*
G02X305742I1511J0D01*
G01Y265047D01*
G02X302720Y265048I-1511J1D01*
G01Y268548D01*
G37*
G36*
G01X703980Y104192D02*
G02X707438Y106044I1729J926D01*
G01X710371Y100567D01*
X710372Y100565D01*
G02X706932Y98680I-1711J-959D01*
G01X703980Y104192D01*
G37*
G36*
G01X712838Y104191D02*
G02X716296Y106045I1729J927D01*
G01X719230Y100567D01*
X719231Y100565D01*
G02X715791Y98679I-1711J-959D01*
G01X712838Y104191D01*
G37*
G36*
G01X296258Y472441D02*
G02X333662I18702J0D01*
G02X296258I-18702J0D01*
G37*
G36*
G01X336094Y334271D02*
G02X333070I-1512J0D01*
G01Y337772D01*
G02X336094Y337771I1512J-1D01*
G01Y334271D01*
G37*
G36*
G01Y359474D02*
G02X333070I-1512J0D01*
G01Y362975D01*
G02X336094Y362974I1512J-1D01*
G01Y359474D01*
G37*
G36*
G01X333070Y287284D02*
G02X336094I1512J0D01*
G01Y283783D01*
G02X333070Y283784I-1512J1D01*
G01Y287284D01*
G37*
G36*
G01X336094Y309074D02*
G02X333070I-1512J0D01*
G01Y312575D01*
G02X336094Y312574I1512J-1D01*
G01Y309074D01*
G37*
G36*
G01X781670Y347206D02*
X781669Y347207D01*
X779234Y349642D01*
X779232Y349644D01*
G02X781330Y351794I1031J1093D01*
G01X783794Y349330D01*
G02X781670Y347206I-1057J-1067D01*
G37*
G36*
G01X764148Y351494D02*
X766612Y349030D01*
G02X764488Y346906I-1057J-1067D01*
G01X764487Y346907D01*
X762052Y349342D01*
X762050Y349344D01*
G02X764148Y351494I1031J1093D01*
G37*
G36*
G01X753430Y344794D02*
X755894Y342330D01*
G02X753770Y340206I-1057J-1067D01*
G01X753769Y340207D01*
X751334Y342642D01*
X751332Y342644D01*
G02X753430Y344794I1031J1093D01*
G37*
G36*
G01X793570Y335406D02*
X793569Y335407D01*
X791134Y337842D01*
X791132Y337844D01*
G02X793230Y339994I1031J1093D01*
G01X795694Y337530D01*
G02X793570Y335406I-1057J-1067D01*
G37*
G36*
G01X776248Y339494D02*
X778712Y337030D01*
G02X776588Y334906I-1057J-1067D01*
G01X776587Y334907D01*
X774152Y337342D01*
X774150Y337344D01*
G02X776248Y339494I1031J1093D01*
G37*
G36*
G01X803770Y333106D02*
X803769Y333107D01*
X801334Y335542D01*
X801332Y335544D01*
G02X803430Y337694I1031J1093D01*
G01X805894Y335230D01*
G02X803770Y333106I-1057J-1067D01*
G37*
G36*
G01X747330Y333794D02*
X749794Y331330D01*
G02X747670Y329206I-1057J-1067D01*
G01X747669Y329207D01*
X745234Y331642D01*
X745232Y331644D01*
G02X747330Y333794I1031J1093D01*
G37*
G36*
G01X765370Y328306D02*
X765369Y328307D01*
X762934Y330742D01*
X762932Y330744D01*
G02X765030Y332894I1031J1093D01*
G01X767494Y330430D01*
G02X765370Y328306I-1057J-1067D01*
G37*
G36*
G01X810019Y237598D02*
X808414D01*
X808377Y237446D01*
G02X805459I-1459J358D01*
G01X805422Y237598D01*
X742151D01*
X740898Y238851D01*
Y274702D01*
X739906Y275694D01*
X712895D01*
X703478Y285111D01*
Y294071D01*
X700348Y297201D01*
Y316262D01*
X709688Y325602D01*
X779621D01*
X794472Y310750D01*
X796492D01*
X799700Y313958D01*
Y314161D01*
X811550Y326011D01*
Y411139D01*
X805189Y417500D01*
X746989D01*
X744950Y419539D01*
Y444511D01*
X746639Y446200D01*
X832011D01*
X866361Y411850D01*
X883161D01*
X886300Y408711D01*
Y285289D01*
X838461Y237450D01*
X826739D01*
X826590Y237598D01*
X811357D01*
X811317Y237580D01*
G02X810059I-629J1364D01*
G01X810019Y237598D01*
G37*
G36*
G01X551124Y149798D02*
Y145478D01*
X551132Y145450D01*
G02X547292I-1920J-568D01*
G01X547300Y145478D01*
Y149798D01*
X547292Y149826D01*
G02X551132I1920J568D01*
G01X551124Y149798D01*
G37*
G36*
G01X536950D02*
Y145478D01*
X536959Y145450D01*
G02X533119I-1920J-568D01*
G01X533128Y145478D01*
Y149798D01*
X533119Y149826D01*
G02X536959I1920J568D01*
G01X536950Y149798D01*
G37*
G36*
G01X522778D02*
Y145478D01*
X522786Y145450D01*
G02X518946I-1920J-568D01*
G01X518954Y145478D01*
Y149798D01*
X518946Y149826D01*
G02X522786I1920J568D01*
G01X522778Y149798D01*
G37*
G36*
G01X508604D02*
Y145478D01*
X508613Y145450D01*
G02X504773I-1920J-568D01*
G01X504782Y145478D01*
Y149798D01*
X504773Y149826D01*
G02X508613I1920J568D01*
G01X508604Y149798D01*
G37*
G36*
G01X466084D02*
Y145478D01*
X466093Y145450D01*
G02X462253I-1920J-568D01*
G01X462262Y145478D01*
Y149798D01*
X462253Y149826D01*
G02X466093I1920J568D01*
G01X466084Y149798D01*
G37*
G36*
G01X451912D02*
Y145478D01*
X451920Y145450D01*
G02X448080I-1920J-568D01*
G01X448088Y145478D01*
Y149798D01*
X448080Y149826D01*
G02X451920I1920J568D01*
G01X451912Y149798D01*
G37*
G36*
G01X437738D02*
Y145478D01*
X437747Y145450D01*
G02X433907I-1920J-568D01*
G01X433916Y145478D01*
Y149798D01*
X433907Y149826D01*
G02X437747I1920J568D01*
G01X437738Y149798D01*
G37*
G36*
G01X423564D02*
Y145478D01*
X423573Y145450D01*
G02X419733I-1920J-568D01*
G01X419742Y145478D01*
Y149798D01*
X419733Y149826D01*
G02X423573I1920J568D01*
G01X423564Y149798D01*
G37*
G36*
G01X558210Y145074D02*
Y140754D01*
X558219Y140726D01*
G02X554379I-1920J-568D01*
G01X554388Y140754D01*
Y145074D01*
X554379Y145102D01*
G02X558219I1920J568D01*
G01X558210Y145074D01*
G37*
G36*
G01X544038D02*
Y140754D01*
X544046Y140726D01*
G02X540206I-1920J-568D01*
G01X540214Y140754D01*
Y145074D01*
X540206Y145102D01*
G02X544046I1920J568D01*
G01X544038Y145074D01*
G37*
G36*
G01X529864D02*
Y140754D01*
X529873Y140726D01*
G02X526033I-1920J-568D01*
G01X526042Y140754D01*
Y145074D01*
X526033Y145102D01*
G02X529873I1920J568D01*
G01X529864Y145074D01*
G37*
G36*
G01X515690D02*
Y140754D01*
X515699Y140726D01*
G02X511859I-1920J-568D01*
G01X511868Y140754D01*
Y145074D01*
X511859Y145102D01*
G02X515699I1920J568D01*
G01X515690Y145074D01*
G37*
G36*
G01X473172D02*
Y140754D01*
X473180Y140726D01*
G02X469340I-1920J-568D01*
G01X469348Y140754D01*
Y145074D01*
X469340Y145102D01*
G02X473180I1920J568D01*
G01X473172Y145074D01*
G37*
G36*
G01X458998D02*
Y140754D01*
X459006Y140726D01*
G02X455166I-1920J-568D01*
G01X455174Y140754D01*
Y145074D01*
X455166Y145102D01*
G02X459006I1920J568D01*
G01X458998Y145074D01*
G37*
G36*
G01X444824D02*
Y140754D01*
X444833Y140726D01*
G02X440993I-1920J-568D01*
G01X441002Y140754D01*
Y145074D01*
X440993Y145102D01*
G02X444833I1920J568D01*
G01X444824Y145074D01*
G37*
G36*
G01X430652D02*
Y140754D01*
X430660Y140726D01*
G02X426820I-1920J-568D01*
G01X426828Y140754D01*
Y145074D01*
X426820Y145102D01*
G02X430660I1920J568D01*
G01X430652Y145074D01*
G37*
G36*
G01X551124Y135625D02*
Y131305D01*
X551132Y131277D01*
G02X547292I-1920J-568D01*
G01X547300Y131305D01*
Y135625D01*
X547292Y135653D01*
G02X551132I1920J568D01*
G01X551124Y135625D01*
G37*
G36*
G01X536950D02*
Y131305D01*
X536959Y131277D01*
G02X533119I-1920J-568D01*
G01X533128Y131305D01*
Y135625D01*
X533119Y135653D01*
G02X536959I1920J568D01*
G01X536950Y135625D01*
G37*
G36*
G01X522778D02*
Y131305D01*
X522786Y131277D01*
G02X518946I-1920J-568D01*
G01X518954Y131305D01*
Y135625D01*
X518946Y135653D01*
G02X522786I1920J568D01*
G01X522778Y135625D01*
G37*
G36*
G01X508604D02*
Y131305D01*
X508613Y131277D01*
G02X504773I-1920J-568D01*
G01X504782Y131305D01*
Y135625D01*
X504773Y135653D01*
G02X508613I1920J568D01*
G01X508604Y135625D01*
G37*
G36*
G01X466084D02*
Y131305D01*
X466093Y131277D01*
G02X462253I-1920J-568D01*
G01X462262Y131305D01*
Y135625D01*
X462253Y135653D01*
G02X466093I1920J568D01*
G01X466084Y135625D01*
G37*
G36*
G01X451912D02*
Y131305D01*
X451920Y131277D01*
G02X448080I-1920J-568D01*
G01X448088Y131305D01*
Y135625D01*
X448080Y135653D01*
G02X451920I1920J568D01*
G01X451912Y135625D01*
G37*
G36*
G01X437738D02*
Y131305D01*
X437747Y131277D01*
G02X433907I-1920J-568D01*
G01X433916Y131305D01*
Y135625D01*
X433907Y135653D01*
G02X437747I1920J568D01*
G01X437738Y135625D01*
G37*
G36*
G01X423564D02*
Y131305D01*
X423573Y131277D01*
G02X419733I-1920J-568D01*
G01X419742Y131305D01*
Y135625D01*
X419733Y135653D01*
G02X423573I1920J568D01*
G01X423564Y135625D01*
G37*
G36*
G01X558210Y130900D02*
Y126581D01*
X558219Y126553D01*
G02X554379I-1920J-568D01*
G01X554388Y126581D01*
Y130900D01*
X554379Y130928D01*
G02X558219I1920J568D01*
G01X558210Y130900D01*
G37*
G36*
G01X544038D02*
Y126581D01*
X544046Y126553D01*
G02X540206I-1920J-568D01*
G01X540214Y126581D01*
Y130900D01*
X540206Y130928D01*
G02X544046I1920J568D01*
G01X544038Y130900D01*
G37*
G36*
G01X529864D02*
Y126581D01*
X529873Y126553D01*
G02X526033I-1920J-568D01*
G01X526042Y126581D01*
Y130900D01*
X526033Y130928D01*
G02X529873I1920J568D01*
G01X529864Y130900D01*
G37*
G36*
G01X515690D02*
Y126581D01*
X515699Y126553D01*
G02X511859I-1920J-568D01*
G01X511868Y126581D01*
Y130900D01*
X511859Y130928D01*
G02X515699I1920J568D01*
G01X515690Y130900D01*
G37*
G36*
G01X473172D02*
Y126581D01*
X473180Y126553D01*
G02X469340I-1920J-568D01*
G01X469348Y126581D01*
Y130900D01*
X469340Y130928D01*
G02X473180I1920J568D01*
G01X473172Y130900D01*
G37*
G36*
G01X458998D02*
Y126581D01*
X459006Y126553D01*
G02X455166I-1920J-568D01*
G01X455174Y126581D01*
Y130900D01*
X455166Y130928D01*
G02X459006I1920J568D01*
G01X458998Y130900D01*
G37*
G36*
G01X444824D02*
Y126581D01*
X444833Y126553D01*
G02X440993I-1920J-568D01*
G01X441002Y126581D01*
Y130900D01*
X440993Y130928D01*
G02X444833I1920J568D01*
G01X444824Y130900D01*
G37*
G36*
G01X430652D02*
Y126581D01*
X430660Y126553D01*
G02X426820I-1920J-568D01*
G01X426828Y126581D01*
Y130900D01*
X426820Y130928D01*
G02X430660I1920J568D01*
G01X430652Y130900D01*
G37*
G36*
G01X715607Y114177D02*
X715602Y114206D01*
X713203Y118682D01*
X713183Y118703D01*
G02X716480Y120469I1384J1376D01*
G01X716485Y120440D01*
X718883Y115964D01*
X718904Y115944D01*
G02X715607Y114177I-1384J-1377D01*
G37*
G36*
G01X706748D02*
X706742Y114206D01*
X704345Y118682D01*
X704325Y118703D01*
G02X707622Y120469I1384J1376D01*
G01X707628Y120440D01*
X710024Y115964D01*
X710045Y115943D01*
G02X706748Y114177I-1384J-1376D01*
G37*
G36*
G01X636867D02*
X636862Y114206D01*
X634463Y118682D01*
X634443Y118703D01*
G02X637740Y120469I1384J1376D01*
G01X637745Y120440D01*
X640143Y115964D01*
X640164Y115944D01*
G02X636867Y114177I-1384J-1377D01*
G37*
G36*
G01X628882Y120469D02*
X628888Y120440D01*
X631284Y115964D01*
X631305Y115943D01*
G02X628008Y114177I-1384J-1376D01*
G01X628002Y114206D01*
X625605Y118682D01*
X625585Y118703D01*
G02X628882Y120469I1384J1376D01*
G37*
G36*
G01X636867Y99216D02*
X636862Y99245D01*
X634463Y103721D01*
X634443Y103742D01*
G02X637740Y105508I1384J1376D01*
G01X637745Y105479D01*
X640143Y101003D01*
X640164Y100983D01*
G02X636867Y99216I-1384J-1377D01*
G37*
G36*
G01X628882Y105508D02*
X628888Y105479D01*
X631284Y101003D01*
X631305Y100982D01*
G02X628008Y99216I-1384J-1376D01*
G01X628002Y99245D01*
X625605Y103721D01*
X625585Y103742D01*
G02X628882Y105508I1384J1376D01*
G37*
G36*
G01X715614Y84226D02*
X715608Y84253D01*
X713181Y88783D01*
X713161Y88803D01*
G02X716473Y90577I1406J1354D01*
G01X716479Y90550D01*
X718907Y86019D01*
X718927Y85999D01*
G02X715614Y84226I-1407J-1353D01*
G37*
G36*
G01X706748Y84256D02*
X706742Y84285D01*
X704346Y88760D01*
X704325Y88780D01*
G02X707622Y90547I1384J1377D01*
G01X707628Y90518D01*
X710025Y86043D01*
X710045Y86022D01*
G02X706748Y84256I-1384J-1376D01*
G37*
G36*
G01X636874Y84226D02*
X636868Y84253D01*
X634441Y88783D01*
X634421Y88803D01*
G02X637733Y90577I1406J1354D01*
G01X637739Y90550D01*
X640167Y86019D01*
X640187Y85999D01*
G02X636874Y84226I-1407J-1353D01*
G37*
G36*
G01X628882Y90547D02*
X628888Y90518D01*
X631285Y86043D01*
X631305Y86022D01*
G02X628008Y84256I-1384J-1376D01*
G01X628002Y84285D01*
X625606Y88760D01*
X625585Y88780D01*
G02X628882Y90547I1384J1377D01*
G37*
G36*
G01X715607Y69295D02*
X715602Y69324D01*
X713203Y73800D01*
X713183Y73821D01*
G02X716480Y75587I1384J1376D01*
G01X716485Y75558D01*
X718883Y71082D01*
X718904Y71062D01*
G02X715607Y69295I-1384J-1377D01*
G37*
G36*
G01X706748D02*
X706742Y69324D01*
X704345Y73800D01*
X704325Y73821D01*
G02X707622Y75587I1384J1376D01*
G01X707628Y75558D01*
X710024Y71082D01*
X710045Y71061D01*
G02X706748Y69295I-1384J-1376D01*
G37*
G36*
G01X636867D02*
X636862Y69324D01*
X634463Y73800D01*
X634443Y73821D01*
G02X637740Y75587I1384J1376D01*
G01X637745Y75558D01*
X640143Y71082D01*
X640164Y71062D01*
G02X636867Y69295I-1384J-1377D01*
G37*
G36*
G01X628882Y75587D02*
X628888Y75558D01*
X631284Y71082D01*
X631305Y71061D01*
G02X628008Y69295I-1384J-1376D01*
G01X628002Y69324D01*
X625605Y73800D01*
X625585Y73821D01*
G02X628882Y75587I1384J1376D01*
G37*
G54D47*
X56102Y24606D03*
X103346Y34449D03*
X590300Y574400D03*
G54D49*
X305906Y182874D03*
G54D52*
X201801Y684252D03*
X225601D03*
G54D50*
X305906Y388386D03*
G54D44*
X18700Y54650D03*
X901000Y21400D03*
X902500Y676000D03*
G54D53*
X488838Y137225D03*
G54D54*
Y164744D03*
G54D46*
X90157Y413583D03*
X309055Y157677D03*
G54D48*
X309252Y413583D03*
G54D55*
X652756Y180000D03*
G54D43*
X89764Y238386D03*
G54D45*
X70866Y98425D03*
Y472441D03*
X875984Y433071D03*
G54D51*
X163189Y669291D03*
G54D56*
X875985Y59055D03*
%LPC*%
G75*
G36*
G01X788814Y292330D02*
X788818Y294071D01*
G03X786179Y294765I-1410J3D01*
G02X785483Y294763I-349J196D01*
G03X782848Y294067I-1225J-699D01*
G01X782841Y290947D01*
G03X785478Y290250I1410J-2D01*
G02X786174I348J-197D01*
G03X788583Y290176I1227J695D01*
G02X789259Y290168I335J-218D01*
G03X790544Y289449I1286J791D01*
G01X792261D01*
G02X792563Y288787I0J-400D01*
G03X792844Y286555I1140J-990D01*
G02X792838Y285894I-228J-328D01*
G03X792165Y284634I837J-1257D01*
G01X792169Y281506D01*
G03X792510Y280552I1510J2D01*
G01X792624Y280412D01*
X789108Y276896D01*
X743403D01*
X743399Y276900D01*
X742901D01*
X742897Y276896D01*
X741217D01*
G03X739099I-1059J-1699D01*
G01X738066D01*
G03X735952I-1057J-1700D01*
G01X734920D01*
G03X732798I-1061J-1698D01*
G01X722317D01*
G03X720203I-1057J-1700D01*
G01X713393D01*
X704680Y285609D01*
Y294569D01*
X701550Y297699D01*
Y315764D01*
X710186Y324400D01*
X717131D01*
G03X720749I1809J1870D01*
G01X722177D01*
G03X725623I1723J1950D01*
G01X768722D01*
X768746Y324394D01*
G03X769786I520J2140D01*
G01X769810Y324400D01*
X779123D01*
X794882Y308641D01*
Y298753D01*
X793700D01*
G03X793699Y295733I0J-1510D01*
G01X794882D01*
Y292699D01*
G02X794317Y292334I-400J0D01*
G03X793694Y292469I-624J-1375D01*
G01X790545D01*
G03X789493Y292042I0J-1509D01*
G02X788814Y292330I-279J287D01*
G37*
G36*
G01X742649Y238800D02*
X742100Y239349D01*
Y240194D01*
X742103Y240212D01*
G03Y240912I-1971J350D01*
G01X742100Y240930D01*
Y243391D01*
X742102Y243405D01*
G03Y243995I-1980J295D01*
G01X742100Y244009D01*
Y246362D01*
X742105Y246385D01*
G03Y247313I-1947J464D01*
G01X742100Y247336D01*
Y249512D01*
X742105Y249535D01*
G03Y250463I-1947J464D01*
G01X742100Y250486D01*
Y252662D01*
X742105Y252685D01*
G03Y253613I-1947J464D01*
G01X742100Y253636D01*
Y255812D01*
X742105Y255835D01*
G03Y256763I-1947J464D01*
G01X742100Y256786D01*
Y265260D01*
X742105Y265283D01*
G03Y266211I-1947J464D01*
G01X742100Y266234D01*
Y268410D01*
X742105Y268433D01*
G03Y269361I-1947J464D01*
G01X742100Y269384D01*
Y271559D01*
X742105Y271582D01*
G03Y272510I-1947J464D01*
G01X742100Y272533D01*
Y274401D01*
X743395Y275696D01*
X789606D01*
X790814Y276904D01*
X790871Y276917D01*
G03X791774Y277511I-319J1468D01*
G02X792429Y277505I325J-232D01*
G03X792853Y277091I1246J852D01*
G02X792866Y276429I-218J-335D01*
G03X792227Y275222I871J-1234D01*
G01X792172Y272091D01*
G03X792849Y270804I1510J-27D01*
G02Y270138I-221J-333D01*
G03X792809Y267648I834J-1259D01*
G02X792807Y266994I-231J-326D01*
G03X792164Y265745I867J-1236D01*
G01X792189Y262622D01*
G03X795209Y262646I1510J12D01*
G01X795184Y265770D01*
G03X794832Y266726I-1510J-13D01*
G02X795135Y267383I307J257D01*
G01X796865Y267400D01*
G03X796835Y270420I-15J1510D01*
G01X795121Y270403D01*
G02X794817Y271067I-4J400D01*
G03X795192Y272037I-1135J996D01*
G01X795247Y275169D01*
G03X794876Y276188I-1510J27D01*
G02X795176Y276850I302J262D01*
G01X796871Y276854D01*
G03X796865Y279874I-3J1510D01*
G01X795134Y279870D01*
G02X794828Y280529I-1J400D01*
G03X795157Y281202I-1149J979D01*
G01X795169Y281260D01*
X796082Y282172D01*
Y286277D01*
X796833Y286274D01*
G03X796845Y289294I6J1510D01*
G01X796082Y289297D01*
Y295733D01*
X796849D01*
G03Y298753I0J1510D01*
G01X796082D01*
Y308641D01*
X800541Y313100D01*
X800761D01*
X813050Y325389D01*
Y389084D01*
X813058Y389111D01*
G03Y390357I-2112J623D01*
G01X813050Y390384D01*
Y392690D01*
G03Y394780I-1938J1045D01*
G01Y411761D01*
X805811Y419000D01*
X747611D01*
X746450Y420161D01*
Y443889D01*
X747261Y444700D01*
X831389D01*
X865739Y410350D01*
X882539D01*
X884800Y408089D01*
Y390346D01*
G03Y387646I1740J-1350D01*
G01Y285911D01*
X837839Y238950D01*
X826739D01*
X826589Y238800D01*
X808042D01*
G03X805794I-1124J-996D01*
G01X803738D01*
X803703Y238814D01*
G03X802613I-545J-1400D01*
G01X802578Y238800D01*
X795134D01*
G03X792268I-1433J-1398D01*
G01X782536D01*
G03X779726Y238855I-1433J-1398D01*
G01X779668Y238800D01*
X779389D01*
X779331Y238855D01*
G03X776521Y238800I-1377J-1453D01*
G01X773088D01*
G03X770222I-1433J-1398D01*
G01X766786D01*
G03X763920I-1433J-1398D01*
G01X742649D01*
G37*
%LPD*%
G75*
G36*
G01X769908Y294122D02*
X769913Y290947D01*
G02X767276Y290250I-1410J-2D01*
G03X766580I-348J-197D01*
G02X763943Y290931I-1227J695D01*
G01X763915Y294089D01*
G02X766556Y294789I1410J13D01*
G03X767257Y294794I349J195D01*
G02X769908Y294126I1241J-670D01*
G01Y294122D01*
G37*
G36*
G01X779362Y290928D02*
G02X776725Y290250I-1410J17D01*
G03X776029I-348J-197D01*
G02X773392Y290959I-1227J695D01*
G01X773425Y294103D01*
G02X776062Y294782I1410J-15D01*
G03X776759Y294783I348J197D01*
G02X779399Y294076I1230J-690D01*
G01X779362Y290928D01*
G37*
G36*
G01X760464Y290945D02*
G02X757827Y290249I-1410J-1D01*
G03X757132I-348J-198D01*
G02X754495Y290944I-1227J695D01*
G01Y294093D01*
G02X757132Y294788I1410J0D01*
G03X757828I348J197D01*
G02X760465Y294093I1227J-694D01*
G01X760464Y290945D01*
G37*
G36*
G01X849476Y314648D02*
X849477Y314647D01*
X852620Y311503D01*
X852622Y311501D01*
G02X850524Y309352I-1031J-1092D01*
G01X847352Y312524D01*
G02X849476Y314648I1057J1067D01*
G37*
G36*
G01X853976Y299148D02*
X853977Y299147D01*
X857120Y296003D01*
X857122Y296001D01*
G02X855024Y293852I-1031J-1092D01*
G01X851852Y297024D01*
G02X853976Y299148I1057J1067D01*
G37*
G36*
G01X849024Y287852D02*
X845852Y291024D01*
G02X847976Y293148I1057J1067D01*
G01X847977Y293147D01*
X851120Y290003D01*
X851122Y290001D01*
G02X849024Y287852I-1031J-1092D01*
G37*
G36*
G01X842476Y287648D02*
X842477Y287647D01*
X845620Y284503D01*
X845622Y284501D01*
G02X843524Y282352I-1031J-1092D01*
G01X840352Y285524D01*
G02X842476Y287648I1057J1067D01*
G37*
G36*
G01X845524Y269352D02*
X842352Y272524D01*
G02X844476Y274648I1057J1067D01*
G01X844477Y274647D01*
X847620Y271503D01*
X847622Y271501D01*
G02X845524Y269352I-1031J-1092D01*
G37*
G36*
G01X839524Y263552D02*
X836352Y266724D01*
G02X838476Y268848I1057J1067D01*
G01X838477Y268847D01*
X841620Y265703D01*
X841622Y265701D01*
G02X839524Y263552I-1031J-1092D01*
G37*
G36*
G01X832676Y262348D02*
X832677Y262347D01*
X835820Y259203D01*
X835822Y259201D01*
G02X833724Y257052I-1031J-1092D01*
G01X830552Y260224D01*
G02X832676Y262348I1057J1067D01*
G37*
G36*
G01X833060Y247433D02*
X829888Y250605D01*
G02X832012Y252729I1057J1067D01*
G01X832013Y252728D01*
X835156Y249584D01*
X835158Y249582D01*
G02X833060Y247433I-1031J-1092D01*
G37*
G54D57*
X865353Y332598D03*
G54D27*
X339331Y49803D03*
X360669Y91929D03*
G54D14*
X38590Y55260D03*
X30270Y48330D03*
X31100Y458733D03*
X26576Y457406D03*
X34132Y521245D03*
X34175Y526969D03*
X64277Y502177D03*
X75399Y502179D03*
X69904Y502077D03*
X41250Y494600D03*
X53524Y521269D03*
Y526995D03*
X75405Y521695D03*
X69778D03*
X64151D03*
X49600Y496050D03*
X55300Y495600D03*
X28800Y549474D03*
X29158Y543855D03*
X29058Y538228D03*
X28782Y555119D03*
X29165Y532612D03*
X33697Y560866D03*
X37660Y566400D03*
X42597Y571789D03*
X61100Y546700D03*
X64400Y539000D03*
X74151Y545516D03*
X74498Y551757D03*
X71002Y539219D03*
X74076Y535966D03*
X75508Y542198D03*
X71002Y542368D03*
X67852Y539219D03*
X71002Y545518D03*
Y558117D03*
X74152Y567565D03*
X71002D03*
Y564396D03*
X74152Y580163D03*
Y577013D03*
X71002Y561266D03*
X67853Y564416D03*
X75066Y563235D03*
X71002Y554967D03*
X67853D03*
X78276Y545566D03*
X67853Y542368D03*
X71002Y548668D03*
X52408Y543876D03*
X64701Y542366D03*
X52603Y549526D03*
X52485Y555153D03*
X53300Y560879D03*
X67853Y570715D03*
X74152Y583312D03*
X64703Y586463D03*
X63456Y555041D03*
X64701Y567566D03*
Y561266D03*
X67853D03*
Y577015D03*
X53524Y532622D03*
X52613Y538242D03*
X53302Y567317D03*
X59200Y582200D03*
X38550Y617950D03*
X50700Y664000D03*
X50800Y667900D03*
X40309Y660700D03*
X71850Y698900D03*
X47150Y665500D03*
X76100Y697100D03*
X97600Y54810D03*
X89070Y62600D03*
X114390Y453185D03*
X102250Y455000D03*
X108300Y435900D03*
X118108Y453159D03*
X121826Y453156D03*
X128968Y452741D03*
X125353Y452385D03*
X132109Y451199D03*
X136021Y451394D03*
X127812Y445066D03*
X117200Y495200D03*
X105920Y477098D03*
X141980Y508590D03*
X97637Y492891D03*
X118900Y522000D03*
X138000Y485900D03*
X102700Y507100D03*
X116500Y477000D03*
X144500Y489500D03*
X92286Y521695D03*
X81032D03*
X86659D03*
X97913D03*
X114500Y490000D03*
X101800Y493000D03*
X137050Y476346D03*
X132774Y497000D03*
X86750Y542368D03*
X126337Y554085D03*
X130311Y546700D03*
X81276Y548766D03*
X119605Y548705D03*
X86750Y539218D03*
X83600Y545518D03*
X89899D03*
X127300Y543200D03*
X89899Y539218D03*
X117200Y546300D03*
X83600Y539219D03*
X86750Y545518D03*
X122600Y557480D03*
X86750Y554965D03*
X130607Y569636D03*
X86750Y558115D03*
X126347Y569556D03*
X83600Y551817D03*
X117400Y567650D03*
X83600Y573865D03*
X86750Y586463D03*
Y583313D03*
X83601Y580164D03*
X89899Y577014D03*
X86750D03*
X83600Y564415D03*
X86750D03*
X83600Y561265D03*
X96570Y581730D03*
X86750Y551815D03*
X123300Y530300D03*
X133800Y528500D03*
X123200Y534600D03*
X143500Y529000D03*
X93744Y542019D03*
X133554Y537374D03*
X93051Y587466D03*
X83600Y567565D03*
X93049Y573864D03*
X89899Y567565D03*
X93048Y580164D03*
X89899Y561265D03*
X86750D03*
X94720Y557158D03*
X92600Y535623D03*
X96371Y534124D03*
X137210Y622030D03*
X134030Y620760D03*
X130630Y620900D03*
X122750Y616950D03*
X122000Y628700D03*
X136100Y656300D03*
X125100Y656700D03*
X123370Y606700D03*
X119600D03*
X118500Y638100D03*
X140700Y657700D03*
X130800Y656100D03*
X127401Y606930D03*
X123500Y613100D03*
X93053Y606734D03*
X142447Y611714D03*
X119000Y633200D03*
X120500Y651800D03*
X134650Y612900D03*
X144750Y606350D03*
X141971Y624700D03*
X98200Y616900D03*
X129800Y630700D03*
X105600Y597000D03*
X105400Y601300D03*
X104600Y609900D03*
X105600Y605900D03*
X104600Y614000D03*
X104500Y618800D03*
X117050Y602000D03*
X116200Y611600D03*
X116023Y607423D03*
X119400Y614100D03*
X116500Y621000D03*
X116400Y616900D03*
X130800Y606700D03*
X138500Y637900D03*
X130500Y638600D03*
X134700D03*
X129903Y634500D03*
X111300Y705500D03*
X107100Y679600D03*
X106879Y707245D03*
X125376Y701124D03*
X106355Y710745D03*
X106635Y701465D03*
X84600Y688000D03*
X119849Y709715D03*
X146301Y460200D03*
X186602Y459767D03*
X197085Y459899D03*
X190278Y459865D03*
X193686Y459799D03*
X176000Y460200D03*
X172200Y460100D03*
X157496Y461248D03*
X166600Y509800D03*
X166700Y499800D03*
X146263Y468562D03*
X186735Y463748D03*
X208370Y491570D03*
X183100Y499800D03*
X170838Y481762D03*
X146300Y502600D03*
X146112Y509412D03*
X158100Y493000D03*
X158400Y513600D03*
X155001Y513707D03*
X182874Y513591D03*
X178869Y513593D03*
X174900Y499800D03*
X166600Y513600D03*
X170700D03*
X172370Y463798D03*
X187000Y468000D03*
X146293Y464338D03*
X146193Y476938D03*
X146293Y472738D03*
X186600Y477700D03*
X187000Y499500D03*
X146500Y492500D03*
X183300Y493100D03*
X145400Y524046D03*
X176100Y473200D03*
X174700Y513900D03*
X182300Y509600D03*
X184780Y526990D03*
X187167Y513167D03*
X191100Y513367D03*
X154500Y487000D03*
X178869Y509793D03*
X209800Y478500D03*
X205447Y487762D03*
X158290Y502380D03*
X182874Y523590D03*
X205516Y467968D03*
X170700Y509800D03*
X170900Y500000D03*
X165900Y524100D03*
X209256Y467946D03*
X172100Y467300D03*
X176800Y492200D03*
X175805Y524073D03*
X206180Y509524D03*
X195149Y513751D03*
X150500Y493000D03*
X190950Y482100D03*
X196200Y482600D03*
X200100Y491700D03*
X146216Y486045D03*
X196243Y486782D03*
X159480Y506590D03*
X155540Y506510D03*
X195300Y498900D03*
X195379Y510158D03*
X150162Y525937D03*
X148527Y519491D03*
X191725Y523074D03*
X195300Y529400D03*
X148409Y575672D03*
X144876Y590854D03*
X148409Y579353D03*
X144876Y587173D03*
X175100Y529100D03*
X203610Y529397D03*
X168390Y532060D03*
X184830Y529960D03*
X149419Y535654D03*
X199400Y529400D03*
X208000Y529300D03*
X149242Y531080D03*
X152584Y532922D03*
X152415Y540014D03*
X194490Y645390D03*
X171020Y611020D03*
X200610Y639611D03*
X207900Y645600D03*
X169000Y640300D03*
X184967Y643983D03*
X200560Y635100D03*
X170940Y614400D03*
X191110Y611050D03*
X191370Y608190D03*
X208700Y625149D03*
X200879Y614739D03*
X145900Y641300D03*
X164800Y640200D03*
X173000Y640400D03*
X193610Y640040D03*
X189500Y639700D03*
X178140Y630330D03*
X196249Y630091D03*
X199400Y628646D03*
X151550Y629800D03*
X163200Y610070D03*
X160420Y610170D03*
X184050Y629500D03*
X181176Y627600D03*
X209093Y615849D03*
X195900Y649350D03*
X203400Y649600D03*
X146800Y629900D03*
X180700Y640460D03*
X204800Y617440D03*
X204642Y621140D03*
X177300Y626800D03*
X204150Y645180D03*
X199600Y650100D03*
X192960Y628510D03*
X187900Y628500D03*
X152700Y640800D03*
X161000Y634300D03*
X157200Y634200D03*
X151130Y703440D03*
X148249Y695765D03*
X206700Y695400D03*
X162100Y711215D03*
X151949Y691715D03*
X175233Y704382D03*
X163349Y702715D03*
X150849Y710215D03*
X163260Y706988D03*
X169070Y696220D03*
X159519Y694455D03*
X193500Y663000D03*
X200400Y694700D03*
X196900Y661350D03*
X206300Y661100D03*
X181300Y679100D03*
X185100Y705600D03*
X184800Y709300D03*
X190200Y671000D03*
X187500Y673100D03*
X272000Y461800D03*
X268350Y461950D03*
X275100Y460300D03*
X259000Y453900D03*
X251700Y443600D03*
X268900Y445150D03*
X244700Y451200D03*
X236100Y445100D03*
X239300Y443800D03*
X243000D03*
X247900Y445300D03*
X260600Y442600D03*
X250500Y451300D03*
X224500Y445600D03*
X254900Y453900D03*
X232200Y445600D03*
X275500Y466200D03*
X275700Y490300D03*
X244900Y527300D03*
X228150Y525750D03*
X275400Y470300D03*
X213100Y476300D03*
X261200Y525400D03*
X242500Y523500D03*
X254500Y509600D03*
X213100Y472900D03*
X275200Y474500D03*
X258100Y516400D03*
X227500Y512200D03*
X265148Y524595D03*
X228700Y490717D03*
X230700Y486658D03*
X249050Y527150D03*
X249640Y495080D03*
X234700Y490900D03*
X258381Y509498D03*
X225914Y523051D03*
X231800Y512100D03*
X223600Y512400D03*
X213359Y480489D03*
X238400Y511300D03*
X265274Y509512D03*
X267800Y479900D03*
X222500Y536161D03*
X211500Y529400D03*
X230900Y581600D03*
X229800Y593200D03*
X247400Y589600D03*
X252593Y547650D03*
X261900Y591300D03*
X247100Y582400D03*
X246611Y551511D03*
X246484Y537139D03*
X269900Y567619D03*
X245743Y546963D03*
X270021Y549394D03*
X257000Y548400D03*
X263216Y554697D03*
X254530Y564300D03*
X251446Y553754D03*
X254500Y579500D03*
X273500Y567400D03*
X254300Y586500D03*
X273400Y590902D03*
X231434Y562844D03*
X234300Y582300D03*
X231200Y576800D03*
X231000Y571900D03*
X257300Y537500D03*
X214900Y529400D03*
X234943Y565199D03*
X254600Y567700D03*
X260731Y561264D03*
X260741Y542700D03*
X264333Y528926D03*
X254905Y555761D03*
X258528Y555161D03*
X259100Y567706D03*
X257000Y571700D03*
X223900Y531200D03*
X228100Y545500D03*
X228800Y542100D03*
X228313Y552169D03*
X262000Y586900D03*
X257851Y580080D03*
X270145Y557526D03*
X261308Y583388D03*
X237100Y590000D03*
X257700Y586400D03*
X261500Y576400D03*
X261600Y580000D03*
X257891Y563786D03*
X257600Y576500D03*
X233607Y557671D03*
X254500Y575070D03*
X261100Y571600D03*
X234800Y572000D03*
X232400Y533200D03*
X248900Y545700D03*
X267957Y537304D03*
X274623Y578896D03*
X271357Y537253D03*
X233036Y550942D03*
X213800Y631200D03*
X212308Y605949D03*
X229796Y610104D03*
X270000Y602400D03*
X255228Y631071D03*
X255648Y626127D03*
X245300Y635700D03*
X254199Y603443D03*
X254600Y597100D03*
X229137Y634881D03*
X266857Y634343D03*
X256001Y612347D03*
X258869Y603050D03*
X266571Y608619D03*
X275470Y608480D03*
X270400Y622870D03*
X219200Y647200D03*
X221900Y630800D03*
X218800Y635600D03*
X230900Y649100D03*
X211706Y645349D03*
X246500Y601500D03*
X234000Y629576D03*
X218200Y651400D03*
X248450Y609900D03*
X266847Y626253D03*
X229063Y638560D03*
X274800Y635000D03*
X222950Y647900D03*
X255570Y616631D03*
X258962Y616384D03*
X236000Y647400D03*
X225900Y630700D03*
X231500Y659100D03*
X228149Y600094D03*
X242710Y604620D03*
X226471Y649129D03*
X243322Y597509D03*
X251314Y598106D03*
X251338Y601506D03*
X258550Y606527D03*
Y610096D03*
X215606Y645806D03*
X229500Y631500D03*
X212900Y619201D03*
X273714Y629870D03*
X245100Y647200D03*
X272200Y648550D03*
X221238Y620524D03*
X234205Y598743D03*
X233258Y595693D03*
X232130Y612950D03*
X251900Y609600D03*
X259777Y638873D03*
X242000Y656400D03*
X255733Y622329D03*
X253196Y706062D03*
X255050Y675750D03*
X254800Y689400D03*
X269200Y699600D03*
X258423Y711343D03*
X268520Y719420D03*
X270900Y667200D03*
X237509Y674915D03*
X266200Y679400D03*
X268384Y662909D03*
X263700Y723500D03*
X264700Y700000D03*
X214270Y695095D03*
X275300Y668749D03*
X217638Y695562D03*
X235000Y692900D03*
X262323Y716917D03*
X255200Y680950D03*
X239400Y677900D03*
X266300Y692574D03*
X311715Y20397D03*
X310353Y62159D03*
X326553Y34687D03*
X339232Y113960D03*
X338743Y122894D03*
X305700Y197600D03*
X295841Y176793D03*
X323582Y179064D03*
X299107Y177740D03*
X295462Y173414D03*
X304231Y265048D03*
Y261048D03*
X322426Y223731D03*
Y227531D03*
X321197Y254433D03*
X322426Y231331D03*
X321782Y215974D03*
X306446Y247874D03*
X305382Y227474D03*
X305498Y213824D03*
X305703Y202165D03*
X306407Y206057D03*
X335000Y226992D03*
X305782Y230874D03*
X335082Y231574D03*
X322301Y220009D03*
X305782Y217274D03*
X305682Y224074D03*
X305782Y220674D03*
X305454Y244461D03*
X334998Y255520D03*
X305373Y251101D03*
X334998Y259033D03*
X306412Y254339D03*
X335060Y262516D03*
X305882Y234274D03*
X305772Y237673D03*
X321700Y246000D03*
X321600Y250000D03*
X305781Y241076D03*
X334582Y287284D03*
Y283784D03*
X307567Y331592D03*
Y328092D03*
Y324092D03*
X304267Y322892D03*
Y318892D03*
Y315392D03*
Y311392D03*
X307567Y310292D03*
Y306292D03*
Y302792D03*
Y298792D03*
X304267Y297692D03*
Y293692D03*
Y290192D03*
Y286192D03*
X328182Y329174D03*
Y325174D03*
Y321674D03*
Y317674D03*
X334582Y312574D03*
Y309074D03*
X328182Y303977D03*
Y299977D03*
Y296477D03*
Y292477D03*
X307567Y285092D03*
Y281092D03*
Y277592D03*
Y273592D03*
X304231Y272548D03*
Y268548D03*
X321281Y266486D03*
X321432Y279090D03*
X321882Y291874D03*
Y304374D03*
X321432Y316885D03*
Y329484D03*
X328913Y274414D03*
X334017Y272000D03*
X337808Y288709D03*
X304267Y373292D03*
Y369292D03*
Y365792D03*
Y361792D03*
X307567Y360692D03*
Y356692D03*
Y353192D03*
Y349192D03*
X304267Y348092D03*
Y344092D03*
Y340592D03*
Y336592D03*
X307567Y335592D03*
X328182Y379518D03*
Y375518D03*
Y372018D03*
Y368018D03*
X334582Y362974D03*
Y359474D03*
Y337771D03*
Y334271D03*
X328182Y354371D03*
Y350371D03*
Y346871D03*
Y342871D03*
X321432Y342082D03*
Y354681D03*
X321202Y376887D03*
X321432Y367279D03*
X335982Y390874D03*
X334000Y382700D03*
X303680Y380972D03*
X316900Y384100D03*
X319679Y387121D03*
X314000Y390500D03*
X335800Y379800D03*
X338800Y435100D03*
X281200Y453500D03*
X333850Y458400D03*
X286700Y457500D03*
X323759Y435145D03*
X327159Y435201D03*
X276634Y498311D03*
X325136Y519316D03*
X333922Y527323D03*
X340961Y511600D03*
X298335Y521458D03*
X304800Y512800D03*
X286797Y516522D03*
X308687Y519193D03*
X302307Y505799D03*
X298907Y505851D03*
X292100Y516000D03*
X297400Y517981D03*
X336600Y504500D03*
X336800Y499967D03*
X325400Y505800D03*
X282403Y474500D03*
X282400Y470200D03*
X328200Y511600D03*
X331200Y508900D03*
X299448Y511300D03*
X277603Y479948D03*
X332821Y515415D03*
X278400Y463300D03*
X280939Y504705D03*
X314400Y505750D03*
X334650Y508900D03*
X300476Y546907D03*
X285800Y549394D03*
X303100Y587000D03*
X292850Y586100D03*
X293271Y557248D03*
X285982Y542502D03*
X325774Y547428D03*
X331700Y587896D03*
X303520Y550085D03*
X296835Y591015D03*
X280646Y557150D03*
X303500Y582200D03*
X333847Y531105D03*
X286195Y530579D03*
X291800Y576708D03*
X333800Y534830D03*
X329840Y572710D03*
X337550Y534619D03*
X295824Y578108D03*
X325475Y572818D03*
X323659Y557310D03*
X334900Y586100D03*
X333512Y553888D03*
X281610Y590260D03*
X324200Y565300D03*
X281490Y586862D03*
X337300Y583000D03*
X336367Y549943D03*
X294107Y560762D03*
X330729Y557268D03*
X298000Y561000D03*
X327059Y557247D03*
X288309Y566467D03*
X328580Y568120D03*
X291000Y570810D03*
X320954Y572631D03*
X277048Y590470D03*
X319529Y562413D03*
X319252Y566509D03*
X285912Y538750D03*
X318736Y549697D03*
X280100Y532100D03*
X322889Y529380D03*
X322843Y533254D03*
X279664Y535473D03*
X328771Y549035D03*
X332808Y547575D03*
X332834Y543993D03*
X337346Y545100D03*
X341316Y545000D03*
X282000Y583500D03*
X298514Y550184D03*
X293087Y530571D03*
X325687Y551368D03*
X319430Y557486D03*
X276839Y582309D03*
X277441Y539882D03*
X308200Y593153D03*
X310292Y532128D03*
X339081Y628173D03*
X339266Y658409D03*
X278443Y648857D03*
X284495Y613130D03*
X286700Y622190D03*
X340100Y631417D03*
X339751Y616882D03*
Y613185D03*
X335036Y603039D03*
X338733D03*
X325300Y648700D03*
X294500Y630600D03*
X298100Y630650D03*
X330400Y644300D03*
X334700Y644500D03*
X335100Y650600D03*
X338100Y635800D03*
X331718Y655832D03*
X329100Y650700D03*
X317689Y599833D03*
X287200Y632600D03*
X290900Y630900D03*
X278769Y700697D03*
X318400Y678400D03*
X325900Y678500D03*
X294804Y695204D03*
X296800Y665081D03*
X311600Y670354D03*
X319600Y670450D03*
X293300Y679700D03*
X321800Y678500D03*
X281000Y678000D03*
X304400Y665100D03*
X316465Y716063D03*
X335750Y664700D03*
X288700Y667900D03*
X340100Y718200D03*
X327250Y701500D03*
X327162Y696776D03*
X282300Y700100D03*
X316000Y671850D03*
X276800Y697925D03*
X338669Y691580D03*
X339804Y679030D03*
X340403Y699400D03*
X340300Y703100D03*
X336200Y677000D03*
X289700Y678830D03*
X280646Y717540D03*
X276100Y677700D03*
X300100Y670300D03*
X304700Y668500D03*
X298570Y743670D03*
X306470Y743570D03*
X278553Y740020D03*
X291700Y737000D03*
X287620Y737300D03*
X290000Y727000D03*
X313873Y735907D03*
X314100Y739300D03*
X370870Y45605D03*
X368059Y57759D03*
X354798Y22452D03*
X386759Y79693D03*
X390456D03*
X342539Y120370D03*
X369253Y88733D03*
X367287Y77118D03*
X381269Y94981D03*
X384666Y93741D03*
X349206Y129948D03*
X390964Y87226D03*
X388700Y89800D03*
X370149Y167337D03*
X370882Y163688D03*
X387202Y164664D03*
X387393Y160859D03*
X404727Y162141D03*
X392102Y175384D03*
X400205Y158209D03*
Y161906D03*
X392458Y171676D03*
X400430Y147190D03*
X361792Y243154D03*
X372888Y208022D03*
X359882Y203458D03*
X347482Y254774D03*
X341882Y251064D03*
X342885Y276301D03*
X342958Y279701D03*
X383170Y329807D03*
X345582Y380874D03*
X344732Y393882D03*
Y390274D03*
X383285Y347114D03*
X383327Y343379D03*
X396561Y351418D03*
X346600Y375000D03*
X344732Y386874D03*
X365100Y348300D03*
X372491Y378025D03*
X365200Y344400D03*
X378492Y378175D03*
X383030Y352442D03*
X367358Y372531D03*
X367471Y369120D03*
X360100Y453500D03*
X342700Y435200D03*
X350491Y453809D03*
X372000Y452100D03*
X369900Y458700D03*
X387450Y454558D03*
X387396Y458126D03*
X384395Y449114D03*
X374700Y460300D03*
X350400Y459000D03*
X381106Y441241D03*
X350400Y462400D03*
X374650Y456771D03*
X346500Y435200D03*
X364500Y453700D03*
X367400Y461200D03*
X355400Y453800D03*
X357900Y450800D03*
X357450Y491450D03*
X364500Y525260D03*
X369300Y508700D03*
X344400Y505400D03*
X344500Y500300D03*
X363500Y464700D03*
X372000Y477710D03*
X355300Y502700D03*
X357700Y499000D03*
X400080Y500854D03*
X384849Y525499D03*
Y521681D03*
X355300Y506100D03*
Y513500D03*
X386367Y474700D03*
X400080Y519500D03*
Y491107D03*
Y523903D03*
Y528243D03*
X389349Y480100D03*
X381986Y515631D03*
X374751Y485636D03*
X374715Y498722D03*
X366950Y464700D03*
X390229Y508189D03*
X341500Y520400D03*
X373699Y521160D03*
X359100Y503200D03*
X374800Y516912D03*
X387450Y467000D03*
X389288Y483500D03*
X358800Y478000D03*
X373800Y503000D03*
X370900Y464700D03*
X378267Y496100D03*
X349088Y500296D03*
X384950Y560496D03*
X383000Y577000D03*
X386305Y581647D03*
X362700Y551200D03*
X361279Y581647D03*
X362100Y574700D03*
X349000Y581360D03*
X379050Y539931D03*
X341740Y535800D03*
X352279Y580294D03*
X346303Y591947D03*
X386723Y544565D03*
X342440Y571770D03*
X361900Y570800D03*
X369500Y542900D03*
X388641Y549747D03*
X400093Y536351D03*
X399726Y562327D03*
X399946Y558677D03*
X344163Y553395D03*
X345259Y557566D03*
X391993Y582154D03*
X362300Y555200D03*
X343840Y566440D03*
X348300Y565400D03*
X364900Y585171D03*
X364964Y588771D03*
X372939Y559838D03*
X346590Y572090D03*
X350278Y572306D03*
X366270Y563400D03*
X373222Y535938D03*
X370247Y546218D03*
X370223Y549965D03*
X384950Y551876D03*
Y555276D03*
X383056Y563675D03*
X400060Y554743D03*
X393912Y571899D03*
X393910Y575305D03*
X341493Y541250D03*
X393912Y578705D03*
X348600Y643500D03*
X344564Y628104D03*
X379400Y641800D03*
X385163Y641354D03*
X391150Y613429D03*
X350500Y647600D03*
X355000Y652160D03*
X374200Y645871D03*
X370200Y636400D03*
X359036Y635900D03*
X383300Y600600D03*
X384410Y633530D03*
X348000Y612661D03*
X352720Y600970D03*
X364014Y593996D03*
X343797Y631417D03*
X381967Y616123D03*
X361227Y630300D03*
X377700Y595000D03*
X383199Y623168D03*
X382438Y608755D03*
X384158Y638105D03*
X380443D03*
X400064Y652598D03*
X384300Y619925D03*
X354102Y660666D03*
X392720Y697500D03*
X376342Y711260D03*
X358296Y672460D03*
X346465Y703185D03*
X364200Y713100D03*
X369600Y693400D03*
X351100Y712100D03*
X396166Y692630D03*
X343200Y667600D03*
X389999Y664697D03*
X367700Y685450D03*
X343338Y679236D03*
X399999Y673422D03*
X396419Y679708D03*
X398983Y706749D03*
X382308Y665022D03*
X396419Y686586D03*
X372350Y698400D03*
X399093Y703350D03*
X380300Y703000D03*
X399154Y699950D03*
X341900Y690350D03*
X346600Y714500D03*
X346000Y684300D03*
X383800Y688400D03*
X380387Y685261D03*
X392500Y673500D03*
X392800Y677600D03*
X341934Y662794D03*
X378595Y664960D03*
X388626Y715509D03*
X392500Y692500D03*
X355298Y711750D03*
X396419Y683186D03*
X469058Y49156D03*
X439200Y22100D03*
X439549Y26339D03*
X439554Y30429D03*
X439302Y34040D03*
X458972Y49634D03*
X462625Y49881D03*
X467300Y20000D03*
X450454Y38147D03*
X448520Y49979D03*
X430800Y22200D03*
X433600Y19900D03*
X428001Y25269D03*
X433400Y63373D03*
X438600Y91033D03*
X419662Y71426D03*
X423340Y71621D03*
X469901Y94047D03*
X415211Y71263D03*
X461736Y111300D03*
X442800Y90934D03*
X496700Y32100D03*
X482693Y42200D03*
X478500Y19775D03*
X506970Y18693D03*
X502830D03*
X512806Y49494D03*
X473151Y50052D03*
X521200Y57600D03*
X496035Y46435D03*
X503814Y56676D03*
X515500Y57900D03*
X486568Y38006D03*
X486114Y41700D03*
X496430Y22890D03*
X491270Y18877D03*
X485674Y32924D03*
X524950Y16120D03*
X473172Y95508D03*
X479147Y102165D03*
X490100Y111300D03*
X486400Y74700D03*
X481800Y71200D03*
X513909Y85849D03*
X510408Y85779D03*
X559200Y36265D03*
X599422Y51662D03*
X568430Y50010D03*
X596489Y14110D03*
X559600Y47600D03*
X575550Y42800D03*
X601311Y13521D03*
X569300Y66274D03*
X545200Y69000D03*
X596300Y66950D03*
X549550Y61900D03*
X597950Y58950D03*
X564500Y64100D03*
X573600Y49750D03*
X584550Y80750D03*
X559900Y88400D03*
X563268Y88872D03*
X540179Y111036D03*
X539346Y114333D03*
X578900Y82500D03*
X551500Y82400D03*
X599682Y103715D03*
X547100Y79900D03*
X578400Y74500D03*
X562160Y178600D03*
X582219Y386612D03*
X599998Y391270D03*
X598964Y354128D03*
X602075Y339970D03*
X586155Y393023D03*
X593064Y400910D03*
X593229Y397308D03*
X666535Y26149D03*
X665800Y7550D03*
X666400Y22200D03*
X619980Y197550D03*
X634000Y187500D03*
X630800Y147600D03*
X634800Y147700D03*
X644100Y203350D03*
X634450Y252100D03*
X631550Y249850D03*
X625926Y247530D03*
X627200Y253550D03*
X625250Y264250D03*
X625550Y244150D03*
Y240750D03*
X645516Y225334D03*
X620750Y258050D03*
X642547Y226992D03*
X632958Y231000D03*
X633109Y234397D03*
X632900Y238000D03*
X628300Y230550D03*
X625700Y235750D03*
X640141Y259859D03*
X640400Y217600D03*
X636491Y217592D03*
X633092Y217496D03*
X659500Y205300D03*
X665500Y201900D03*
X662900Y205300D03*
X645400Y264050D03*
X620160Y203500D03*
X660700Y292200D03*
X634830Y292095D03*
X638453Y291949D03*
X633400Y274600D03*
X657500Y281500D03*
X652850Y269600D03*
X642300Y276450D03*
X649000Y273500D03*
X652100Y279300D03*
X648000Y281300D03*
X656700Y305607D03*
X664600Y306100D03*
X648700Y303600D03*
X652500Y305707D03*
X638603Y296320D03*
X642003Y296249D03*
X645403Y296229D03*
X631069Y292512D03*
X654670Y391494D03*
X616428Y379533D03*
X626772Y371336D03*
X654600Y367600D03*
X639318Y354003D03*
X643082Y353941D03*
X629239Y387969D03*
X620100Y384100D03*
X608600Y362600D03*
X632220Y389694D03*
X607800Y382362D03*
X607100Y351200D03*
X638360Y383805D03*
X642270Y383869D03*
X605400Y393400D03*
X618600Y364375D03*
X609240Y370337D03*
X616900Y343000D03*
X615150Y364200D03*
X640968Y370425D03*
X606626Y354723D03*
X637353Y379591D03*
X657900Y443200D03*
X655100Y436900D03*
X636963Y405999D03*
X632180Y397968D03*
X654300Y504100D03*
X613000Y463000D03*
X666216Y470684D03*
X632800Y561600D03*
X620160Y544793D03*
X635970Y557600D03*
X638660Y568043D03*
X616160Y542700D03*
X614000Y561250D03*
X606600Y551100D03*
X677770Y196410D03*
X730550Y179050D03*
X732000Y185900D03*
X716650Y174400D03*
X674300Y198900D03*
X718121Y256326D03*
X718089Y246834D03*
X718098Y259423D03*
X718072Y265748D03*
X718089Y249984D03*
X718129Y253144D03*
X693800Y264300D03*
X725466Y200819D03*
X707923Y219765D03*
X708900Y214500D03*
X718111Y224802D03*
X706500Y212150D03*
X709615Y223228D03*
X718111Y231101D03*
X696300Y215750D03*
X702900Y212350D03*
X707679Y233664D03*
X718111Y227952D03*
X722322Y200935D03*
X704279Y226664D03*
X705529Y231064D03*
X705779Y236764D03*
X706079Y240664D03*
X710716Y235827D03*
X714945Y234230D03*
X726988Y204312D03*
X718123Y201101D03*
X710079Y203664D03*
X718895Y207125D03*
X705364Y205864D03*
X713168Y207689D03*
X718111Y221653D03*
X733859Y215355D03*
X718110Y234252D03*
X709679Y239164D03*
X727560Y215355D03*
X716116Y207469D03*
X718111Y237401D03*
X709079Y229564D03*
X703979Y219995D03*
X718111Y240550D03*
X711812Y243700D03*
X714961D03*
X730709Y215355D03*
X724410D03*
X732264Y204312D03*
X703320Y203900D03*
X733859Y212206D03*
X729800Y208400D03*
X730709Y221654D03*
X733858D03*
X724410D03*
Y234252D03*
Y240551D03*
Y246850D03*
Y253150D03*
Y227953D03*
Y265748D03*
Y259449D03*
X704579Y261964D03*
X682030Y253630D03*
X706100Y250000D03*
X690600Y230700D03*
X691243Y211743D03*
X692600Y201300D03*
X677800Y215900D03*
X724410Y281496D03*
X730710D03*
X733859D03*
X721820Y315750D03*
X733859Y278346D03*
X730708Y290944D03*
X724409D03*
X727559Y278346D03*
X718340Y315800D03*
X706796Y295829D03*
X726895Y309117D03*
X711799Y304234D03*
X713339Y306954D03*
X724063Y306305D03*
X698039Y285854D03*
X707834Y293060D03*
X707079Y286964D03*
X704079Y300964D03*
X719200Y307400D03*
X705579Y298464D03*
X695508Y288964D03*
X710679Y267894D03*
X721230Y284653D03*
X718099Y290964D03*
X710329Y285214D03*
X718117Y281465D03*
X718080Y284653D03*
X701708Y292364D03*
X706277Y279162D03*
X718072Y278346D03*
X708409Y276771D03*
X733892Y297246D03*
X730708Y297243D03*
X714619Y303884D03*
X692750Y293200D03*
X718109Y272034D03*
X694307Y283485D03*
X722468Y308964D03*
X727558Y297243D03*
X733859Y272048D03*
X690579Y299964D03*
X675555Y318736D03*
X672350Y317600D03*
X724409Y297243D03*
X700323Y283078D03*
X716300Y331340D03*
X733859Y284646D03*
X695300Y306700D03*
X718099Y287814D03*
X712410Y331320D03*
X702250Y329650D03*
X733857Y290944D03*
X727558D03*
X730300Y314900D03*
X724410Y272047D03*
Y278346D03*
Y284645D03*
X669950Y310950D03*
X681800Y287950D03*
X718137Y275186D03*
X702939Y281484D03*
X718109Y268934D03*
X714949Y287814D03*
X718300Y362900D03*
X722500Y353000D03*
X718000D03*
X713500Y362900D03*
X729900Y393200D03*
X708300Y445800D03*
X709006Y410206D03*
X721504Y402321D03*
X691813Y407210D03*
X691874Y410741D03*
X691873Y403800D03*
X690550Y453850D03*
X690300Y460200D03*
X720900Y412900D03*
X677275Y485625D03*
X683583Y485841D03*
X702824Y476476D03*
X682400Y463400D03*
X730600Y493100D03*
X716078Y492334D03*
X672500Y507100D03*
X696000Y508400D03*
X715391Y479109D03*
X725000Y576100D03*
X714800Y567956D03*
X710000Y549100D03*
X710100Y545600D03*
X705176Y593429D03*
X717450Y551554D03*
X697200Y529200D03*
X705676Y562429D03*
X702515Y597064D03*
X693900Y597800D03*
X703800Y608400D03*
X712708Y603038D03*
X723369Y599835D03*
X722122Y611840D03*
X795832Y66750D03*
X787360Y35650D03*
X776300Y47600D03*
X769812Y53660D03*
X756431Y54010D03*
X736803Y52087D03*
X779400Y54750D03*
X746500Y47200D03*
X780815Y47062D03*
X776600Y35250D03*
X762765Y42200D03*
X781250Y101750D03*
X779594Y126865D03*
X762000Y113000D03*
X763825Y89975D03*
X776500Y82700D03*
X750500Y118500D03*
X750600Y114200D03*
X769500Y91000D03*
X792600Y101300D03*
X772800Y107550D03*
X776850Y115050D03*
X738160Y199480D03*
X749900Y185200D03*
X786343Y179959D03*
X745700Y185900D03*
X769100Y187800D03*
X786388Y183429D03*
X772810Y179901D03*
X772700Y183300D03*
X737000Y185900D03*
X765900Y191900D03*
X768579Y203964D03*
X764900Y207200D03*
X768505Y243702D03*
X784277Y243713D03*
X771654Y253150D03*
X765355Y265749D03*
X771654Y259449D03*
Y265749D03*
X784277Y246863D03*
X784267Y259426D03*
X759056Y253150D03*
X765354Y246850D03*
X784277Y253162D03*
X746457Y240552D03*
X752757D03*
X759056D03*
X746421Y253149D03*
X746457Y246850D03*
X752720Y253149D03*
X752757Y246851D03*
X765355Y253150D03*
X759056Y246851D03*
X746433Y265761D03*
X746457Y259449D03*
X752757D03*
Y265749D03*
X765355Y259449D03*
X759056Y265749D03*
X759031Y259461D03*
X777976Y265761D03*
X784267Y256276D03*
X793672Y243709D03*
X799991Y249972D03*
X799972Y262588D03*
X796822D03*
Y256289D03*
X790551Y259486D03*
X790538Y265723D03*
X777976Y259461D03*
X761600Y207300D03*
X787402Y240552D03*
Y243701D03*
X793700Y256262D03*
X752759Y218499D03*
X755909Y218514D03*
X790550Y253150D03*
X799972Y256309D03*
X781080Y265763D03*
X784258Y262618D03*
X777967Y262576D03*
X790523Y256289D03*
X800021Y243717D03*
X795593Y206063D03*
X777953Y256300D03*
X781300Y207800D03*
X774803Y265749D03*
X737009Y240552D03*
X746457Y215355D03*
X737029Y215337D03*
X743279Y215364D03*
X740158Y215355D03*
X743279Y212196D03*
X741294Y208274D03*
X743008Y206059D03*
X762205Y221654D03*
X784252D03*
X777953D03*
X790551D03*
X740158D03*
X755906D03*
X746457D03*
X793701Y234254D03*
X781127Y246863D03*
X793672Y240560D03*
X796821Y246859D03*
X793701Y227954D03*
X796850Y221654D03*
X793674Y265758D03*
X793699Y262634D03*
X768504Y215355D03*
X763963Y331837D03*
X766437Y329363D03*
X748737Y330263D03*
X762229Y290933D03*
X752756Y278346D03*
X759073Y287810D03*
X774826Y268910D03*
X737009Y281496D03*
X740159Y278345D03*
Y281496D03*
X759031Y275209D03*
X765356Y272048D03*
Y275197D03*
Y278347D03*
X746457Y272047D03*
Y275197D03*
X752757D03*
X752731Y272060D03*
X762181D03*
X759031D03*
X762206Y275197D03*
Y278347D03*
X790551Y284646D03*
X781100Y287800D03*
X787419Y278354D03*
X737007Y290944D03*
X749579Y297254D03*
X787402Y297243D03*
X781102Y297244D03*
X771654Y297243D03*
X759058Y300414D03*
X768503Y287794D03*
X774802D03*
X787400Y287795D03*
X749607Y275197D03*
X774789Y275174D03*
X784221Y284652D03*
X777915Y281496D03*
X762189Y281514D03*
X768489Y281474D03*
X777953Y275198D03*
Y278347D03*
X784290Y272047D03*
X743306Y290944D03*
X749606Y278346D03*
X749593Y284670D03*
X799999Y290944D03*
Y284645D03*
Y278345D03*
X799974Y272058D03*
X793701Y300393D03*
X790519Y272053D03*
X790550Y287795D03*
X749605Y290944D03*
X762204Y287794D03*
X781064Y272047D03*
X784243Y278318D03*
X780300Y309300D03*
X740157Y297243D03*
X737008Y297244D03*
X740158Y284646D03*
X744881Y309000D03*
X743306Y297243D03*
X784252Y268885D03*
X796839Y290934D03*
X787438Y275197D03*
X796832Y272064D03*
X796875Y304331D03*
X796862Y281522D03*
X784249Y281464D03*
X787426Y272060D03*
X790551Y278384D03*
X743308Y284646D03*
X746457D03*
X737009D03*
X744400Y322800D03*
X746456Y297243D03*
X765353Y287794D03*
X771653D03*
X777952D03*
X784251D03*
X762225Y297227D03*
X755898Y287804D03*
X746456Y290944D03*
X740157D03*
X793700Y297243D03*
X796849D03*
X790545Y290959D03*
X793694D03*
X793703Y287797D03*
X796839Y287784D03*
X793675Y284637D03*
X793679Y281508D03*
X793675Y278357D03*
X796868Y278364D03*
X793737Y275196D03*
X793682Y272064D03*
X793683Y268879D03*
X796850Y268910D03*
X763081Y350437D03*
X765555Y347963D03*
X775181Y338437D03*
X777655Y335963D03*
X780263Y350737D03*
X782737Y348263D03*
X792163Y338937D03*
X794637Y336463D03*
X746263Y332737D03*
X752363Y343737D03*
X754837Y341263D03*
X790357Y377781D03*
X735300Y401957D03*
X774700Y483600D03*
X747125Y483924D03*
X743726Y483813D03*
X755500Y492600D03*
X768500Y480000D03*
X740253Y483893D03*
X745700Y498250D03*
X742300Y498200D03*
X759000Y482900D03*
X759169Y497414D03*
X750600Y497400D03*
X759200Y508000D03*
X777600Y512200D03*
X781700Y510900D03*
X736600Y500000D03*
X780750Y496750D03*
X781050Y492550D03*
X757099Y530082D03*
X763809Y537191D03*
X782709Y537691D03*
X795922Y531500D03*
X747200Y611900D03*
X826925Y57425D03*
X802786Y57150D03*
X841300Y54200D03*
X818785Y50692D03*
X803000Y117100D03*
X813349Y73142D03*
X809349Y73197D03*
X821962Y189277D03*
X801385Y183067D03*
X801340Y179597D03*
X831504Y199129D03*
X843419Y261781D03*
X840591Y264609D03*
X837619Y255281D03*
X834791Y258109D03*
X831609Y261291D03*
X828781Y264119D03*
X836955Y245662D03*
X834127Y248490D03*
X830945Y251672D03*
X828117Y254500D03*
X832148Y204444D03*
X816079Y250464D03*
X808923Y245979D03*
X806968Y253464D03*
X816900Y231700D03*
X803160Y259454D03*
X803150Y256336D03*
X807177Y261023D03*
X814262Y218950D03*
X810277Y243190D03*
X810688Y238944D03*
X803129Y240535D03*
X803158Y237414D03*
X806862Y243302D03*
X806918Y237804D03*
X826000Y233400D03*
X828000Y243100D03*
X854419Y307581D03*
X851591Y310409D03*
X848409Y313591D03*
X845581Y316419D03*
X858919Y292081D03*
X856091Y294909D03*
X852909Y298091D03*
X850081Y300919D03*
X852919Y286081D03*
X850091Y288909D03*
X846909Y292091D03*
X844081Y294919D03*
X849419Y267581D03*
X846591Y270409D03*
X843409Y273591D03*
X840581Y276419D03*
X847419Y280581D03*
X844591Y283409D03*
X841409Y286591D03*
X838581Y289419D03*
X837409Y267791D03*
X834581Y270619D03*
X822817Y331022D03*
X825646Y328193D03*
X803300Y303700D03*
X823250Y319350D03*
X814450Y306950D03*
X810079Y271264D03*
X809968Y290464D03*
X808400Y300900D03*
X812164Y279674D03*
X802363Y336637D03*
X804837Y334163D03*
X817514Y336325D03*
X820343Y333496D03*
X857581Y391433D03*
X817700Y385700D03*
X851100Y407500D03*
X861000Y410500D03*
X806400Y398700D03*
X810100Y404934D03*
X857000Y410600D03*
X850950Y489300D03*
X800800Y526900D03*
X829500Y481500D03*
X813150Y533450D03*
X883240Y301973D03*
X888668Y322100D03*
X886540Y388996D03*
X872750Y403400D03*
G54D21*
X65900Y671000D03*
X65700Y660900D03*
X70600Y665800D03*
X60700Y665900D03*
X70800Y660700D03*
X60800Y660900D03*
X70700Y671000D03*
X60600Y670900D03*
X65714Y665850D03*
X135019Y706095D03*
X130019D03*
X139916Y705822D03*
X130019Y724095D03*
X135019Y714845D03*
Y719095D03*
Y723595D03*
Y710595D03*
X130019Y720495D03*
Y716895D03*
Y713295D03*
Y709695D03*
X139916Y723822D03*
Y720222D03*
Y716622D03*
Y713022D03*
Y709422D03*
X295634Y710070D03*
X290520Y715120D03*
X300620Y715220D03*
X290720Y705120D03*
X300720Y704920D03*
X290620Y710120D03*
X300520Y710020D03*
X295620Y705120D03*
X295820Y715220D03*
X371400Y606400D03*
X358900Y612800D03*
X358800Y606300D03*
X365300Y606500D03*
X371400Y612700D03*
X371300Y618800D03*
X365500Y619000D03*
X358900Y618800D03*
X365164Y612620D03*
X468000Y35400D03*
X464000Y35500D03*
X468000Y39500D03*
Y31500D03*
X472000Y35500D03*
X601500Y363600D03*
G54D26*
X201801Y684252D03*
X225601D03*
G54D38*
X651575Y20039D03*
X608267D03*
X641732Y126811D03*
X624015D03*
X651575Y72441D03*
X608267D03*
X730315Y20039D03*
X687007D03*
X720472Y126811D03*
X702755D03*
X730315Y72441D03*
X687007D03*
G54D33*
X421653Y130709D03*
X428740Y125985D03*
X435827Y130709D03*
X442913Y125985D03*
X450000Y130709D03*
X457086Y125985D03*
X464173Y130709D03*
X471260Y125985D03*
X428740Y131496D03*
X442913D03*
X457086D03*
X471260D03*
X421653Y136221D03*
X435827D03*
X450000D03*
X464173D03*
X421653Y144882D03*
X428740Y140158D03*
X435827Y144882D03*
X442913Y140158D03*
X450000Y144882D03*
X457086Y140158D03*
X464173Y144882D03*
X471260Y140158D03*
X421653Y150394D03*
X428740Y145670D03*
X435827Y150394D03*
X442913Y145670D03*
X450000Y150394D03*
X457086Y145670D03*
X464173Y150394D03*
X471260Y145670D03*
X421653Y159055D03*
X428740Y154331D03*
X435827Y159055D03*
X442913Y154331D03*
X450000Y159055D03*
X457086Y154331D03*
X464173Y159055D03*
X471260Y154331D03*
X421653Y164567D03*
X428740Y159843D03*
X435827Y164567D03*
X442913Y159843D03*
X450000Y164567D03*
X457086Y159843D03*
X464173Y164567D03*
X471260Y159843D03*
X421653Y173229D03*
X428740Y168504D03*
X435827Y173229D03*
X442913Y168504D03*
X450000Y173229D03*
X457086Y168504D03*
X464173Y173229D03*
X471260Y168504D03*
X421653Y178740D03*
X428740Y174016D03*
X435827Y178740D03*
X442913Y174016D03*
X450000Y178740D03*
X457086Y174016D03*
X464173Y178740D03*
X471260Y174016D03*
X506693Y130709D03*
X513779Y125985D03*
X520866Y130709D03*
X527953Y125985D03*
X535039Y130709D03*
X513779Y131496D03*
X527953D03*
X506693Y136221D03*
X520866D03*
X535039D03*
X506693Y144882D03*
X513779Y140158D03*
X520866Y144882D03*
X527953Y140158D03*
X535039Y144882D03*
X506693Y150394D03*
X513779Y145670D03*
X520866Y150394D03*
X527953Y145670D03*
X535039Y150394D03*
X506693Y159055D03*
X513779Y154331D03*
X520866Y159055D03*
X527953Y154331D03*
X535039Y159055D03*
X506693Y164567D03*
X513779Y159843D03*
X520866Y164567D03*
X527953Y159843D03*
X535039Y164567D03*
X506693Y173229D03*
X513779Y168504D03*
X520866Y173229D03*
X527953Y168504D03*
X535039Y173229D03*
X506693Y178740D03*
X513779Y174016D03*
X520866Y178740D03*
X527953Y174016D03*
X535039Y178740D03*
X542126Y125985D03*
X549212Y130709D03*
X556299Y125985D03*
X542126Y131496D03*
X556299D03*
X549212Y136221D03*
X542126Y140158D03*
X549212Y144882D03*
X556299Y140158D03*
X542126Y145670D03*
X549212Y150394D03*
X556299Y145670D03*
X542126Y154331D03*
X549212Y159055D03*
X556299Y154331D03*
X542126Y159843D03*
X549212Y164567D03*
X556299Y159843D03*
X542126Y168504D03*
X549212Y173229D03*
X556299Y168504D03*
X542126Y174016D03*
X549212Y178740D03*
X556299Y174016D03*
X638780Y69685D03*
X629921D03*
X621063D03*
X638780Y114567D03*
X635827Y120079D03*
X629921Y114567D03*
X626969Y120079D03*
X621063Y114567D03*
X618110Y120079D03*
X638780Y99606D03*
X635827Y105118D03*
X629921Y99606D03*
X621063D03*
X626969Y105118D03*
X618110D03*
X638780Y84646D03*
X635827Y90157D03*
X626969D03*
X629921Y84646D03*
X621063D03*
X618110Y90157D03*
X635827Y75197D03*
X626969D03*
X618110D03*
X717520Y69685D03*
X708661D03*
X699803D03*
X717520Y114567D03*
X714567Y120079D03*
X708661Y114567D03*
X705709Y120079D03*
X699803Y114567D03*
X696850Y120079D03*
X717520Y99606D03*
X714567Y105118D03*
X708661Y99606D03*
X699803D03*
X705709Y105118D03*
X696850D03*
X717520Y84646D03*
X714567Y90157D03*
X705709D03*
X708661Y84646D03*
X699803D03*
X696850Y90157D03*
X714567Y75197D03*
X705709D03*
X696850D03*
G54D30*
X305906Y388386D03*
G54D11*
X8500Y428279D03*
Y438279D03*
Y448279D03*
Y458279D03*
Y433279D03*
Y443279D03*
Y453279D03*
Y468279D03*
Y478279D03*
Y488279D03*
Y498279D03*
Y508279D03*
Y518279D03*
Y528279D03*
Y463279D03*
Y473279D03*
Y483279D03*
Y493279D03*
Y503279D03*
Y513279D03*
Y523279D03*
Y538279D03*
Y548279D03*
Y558279D03*
Y568279D03*
Y578279D03*
Y588279D03*
Y533279D03*
Y543279D03*
Y553279D03*
Y563279D03*
Y573279D03*
Y583279D03*
Y593279D03*
Y598279D03*
Y608279D03*
Y618279D03*
Y628279D03*
Y638279D03*
Y648279D03*
Y658279D03*
Y603279D03*
Y613279D03*
Y623279D03*
Y633279D03*
Y643279D03*
Y653279D03*
Y668279D03*
Y678279D03*
Y688279D03*
Y698279D03*
Y708279D03*
Y718279D03*
Y663279D03*
Y673279D03*
Y683279D03*
Y693279D03*
Y703279D03*
Y713279D03*
X75534Y625175D03*
X80334D03*
X99600Y673500D03*
Y678500D03*
X86500Y703100D03*
X86600Y708300D03*
X96800Y662000D03*
X90200Y667100D03*
X85400D03*
X99600Y683500D03*
X134223Y691027D03*
X122435Y666782D03*
Y661982D03*
X144057Y755280D03*
X139057D03*
X155400Y717700D03*
X204057Y755280D03*
X194057D03*
X184057D03*
X174057D03*
X164057D03*
X154057D03*
X149057D03*
X159057D03*
X169057D03*
X179057D03*
X189057D03*
X199057D03*
X209057D03*
X249500Y719500D03*
Y724300D03*
X274057Y755280D03*
X264057D03*
X254057D03*
X244057D03*
X234057D03*
X224057D03*
X214057D03*
X219057D03*
X229057D03*
X239057D03*
X249057D03*
X259057D03*
X269057D03*
X249500Y729100D03*
Y733900D03*
Y738700D03*
X315120Y8500D03*
X310120D03*
X305120D03*
X300120D03*
X296020Y9420D03*
Y14420D03*
Y19420D03*
Y24420D03*
Y29420D03*
X321382Y197574D03*
X335132Y195874D03*
X305862Y210014D03*
X334882Y215874D03*
Y220874D03*
X321382Y202374D03*
X335132Y205974D03*
X335200Y640100D03*
X330400D03*
X325600D03*
X330200Y709300D03*
X334650Y689700D03*
X335350Y684650D03*
X315520Y711720D03*
X325700Y711600D03*
X320320Y711720D03*
X305500Y721000D03*
X310500D03*
X304150Y674700D03*
X299350D03*
X324057Y755280D03*
X314057D03*
X304057D03*
X294057D03*
X284057D03*
X279057D03*
X289057D03*
X299057D03*
X309057D03*
X319057D03*
X329057D03*
X305500Y726000D03*
X310500D03*
X520000Y63400D03*
X515200Y66440D03*
X520585Y68348D03*
X508668Y79607D03*
X503550Y79500D03*
X511100Y75060D03*
X506100D03*
X511100Y70060D03*
X525200Y71440D03*
X516628Y71806D03*
X600700Y35700D03*
X595500Y35600D03*
X595700Y29800D03*
X600900Y29700D03*
X576610Y388416D03*
Y393416D03*
X576512Y369625D03*
Y364825D03*
X581312Y369625D03*
Y364825D03*
X576610Y398416D03*
Y403416D03*
Y408416D03*
Y413416D03*
X609200Y330400D03*
X658000Y431500D03*
Y409000D03*
Y414000D03*
Y426000D03*
Y420500D03*
X642700Y454400D03*
X642500Y449100D03*
X642600Y459500D03*
X621600Y486619D03*
X626958Y486419D03*
X642500Y464700D03*
X629500Y482500D03*
Y477000D03*
Y471500D03*
X635000Y482500D03*
Y476500D03*
Y471000D03*
X657000Y555000D03*
X662000D03*
X661887Y560010D03*
X656887D03*
X723900Y326350D03*
X718940Y326270D03*
X714900Y453600D03*
X715200Y459600D03*
X706700Y413900D03*
X710200Y417400D03*
Y422900D03*
Y427900D03*
X698700Y417600D03*
Y423100D03*
Y428100D03*
X676000Y431000D03*
X671000D03*
Y421000D03*
X676000D03*
X671000Y426000D03*
X676000D03*
X715200Y465000D03*
X689500Y518500D03*
Y524000D03*
X694738Y523940D03*
X694690Y519034D03*
X687015Y658100D03*
Y653300D03*
Y648500D03*
Y643700D03*
Y682100D03*
X673950Y686104D03*
Y691104D03*
Y696104D03*
Y701104D03*
Y706104D03*
X687015Y677300D03*
Y672500D03*
Y667700D03*
Y662900D03*
X780100Y8500D03*
X775100D03*
X770100D03*
X765100D03*
X760100D03*
X755100D03*
X750100D03*
X745100D03*
X787895D03*
X797895D03*
X792895D03*
X754000Y172700D03*
Y177500D03*
X798359Y351659D03*
X795193Y355540D03*
X791786Y359001D03*
X807895Y8500D03*
X817895D03*
X827895D03*
X832895D03*
X822895D03*
X812895D03*
X802895D03*
X842600Y339400D03*
X841100Y332300D03*
X826993Y358840D03*
X821502Y358356D03*
X827145Y363638D03*
X821653Y363488D03*
X826900Y332500D03*
X825300Y339900D03*
X825100Y347300D03*
X828100Y352900D03*
X809792Y379122D03*
X814592D03*
X809792Y374322D03*
X814592D03*
X842900Y347200D03*
X840800Y352800D03*
X864727Y398458D03*
X827000Y516000D03*
X832000D03*
Y521000D03*
X827000D03*
X843900Y464000D03*
X848700Y465200D03*
Y470600D03*
X874727Y398458D03*
X869727D03*
G54D36*
X564803Y24409D03*
X574803D03*
X584803D03*
X753780D03*
X763780D03*
X773780D03*
X801024D03*
X811024D03*
X821024D03*
G54D23*
X197243Y589764D03*
X203542Y592913D03*
X168898Y548819D03*
X184645Y589764D03*
X175197D03*
X209842Y583464D03*
X187795Y570866D03*
X184646Y577165D03*
X187795D03*
X190945D03*
X190944Y574016D03*
X190945Y570866D03*
X187795Y574016D03*
X184646D03*
Y570866D03*
X187795Y564567D03*
X194094Y567716D03*
X190945D03*
X187795D03*
X184646D03*
X206692Y592913D03*
X184645Y539370D03*
X194094D03*
X203542Y545671D03*
X197243Y539371D03*
X206692Y555120D03*
X194093D03*
X184646D03*
X153149Y536221D03*
X172048Y555120D03*
Y589764D03*
X168898Y570866D03*
X156299D03*
X197243Y592913D03*
X200393Y589764D03*
X187794Y586614D03*
X203542Y589764D03*
X187795Y592914D03*
X209841Y574016D03*
X206692D03*
X165745Y564567D03*
X168895D03*
X159449Y561417D03*
X165748D03*
X172047D03*
X162598Y558268D03*
X168898D03*
X165748Y555118D03*
X159449D03*
X168898Y567717D03*
X159449Y570866D03*
X168898Y583464D03*
Y577165D03*
X159449Y586614D03*
X162598Y580315D03*
Y586614D03*
X165748D03*
X168898D03*
X159449Y577165D03*
X156299D03*
X168898Y580315D03*
X159449D03*
X162598Y577165D03*
X165748Y580315D03*
X162598Y583464D03*
X165748Y570866D03*
Y567717D03*
X162598D03*
X172047Y570866D03*
X162597Y555118D03*
X197243Y551970D03*
X194093D03*
X200395Y555120D03*
X181497Y551970D03*
Y589764D03*
X187795Y555120D03*
X206692Y564569D03*
Y561419D03*
Y558269D03*
Y567718D03*
X203543Y574017D03*
X206692Y583465D03*
X194093Y586614D03*
X178347Y551970D03*
X175197D03*
Y558268D03*
X178347Y589764D03*
X190945Y542519D03*
X172047Y545669D03*
Y551970D03*
X159449Y545671D03*
X162599Y545669D03*
X165749D03*
X184646Y548821D03*
Y545671D03*
X209842Y567717D03*
X184645Y542519D03*
X206692Y542521D03*
X209841Y577165D03*
X159449Y542521D03*
X156299Y545671D03*
X168898Y592913D03*
X181497Y545671D03*
X209842Y545669D03*
X165749Y548819D03*
X175197Y545671D03*
X162599Y542519D03*
X168898D03*
X156299Y542521D03*
X181496Y542520D03*
X159449Y548821D03*
X206692Y589763D03*
X172047Y548819D03*
X168898Y551969D03*
X162599Y548821D03*
X194093Y589764D03*
Y592913D03*
X162598Y561417D03*
X168898Y555119D03*
X181497Y548821D03*
X178346Y545670D03*
X206692Y586614D03*
X209842Y586613D03*
X209841Y592913D03*
X162595Y564567D03*
X162598Y570866D03*
X203542Y548821D03*
X172048Y564569D03*
X172047Y567717D03*
X175298Y577266D03*
X209842Y558268D03*
X190944Y589764D03*
Y592913D03*
X197244Y586615D03*
X200393Y586614D03*
X194094Y542519D03*
X209842Y564567D03*
X200393Y548819D03*
X209842Y561417D03*
Y589763D03*
X206692Y580315D03*
X209841D03*
X200393Y545669D03*
X206692Y545671D03*
X200393Y592913D03*
X159448Y589764D03*
Y592913D03*
X162598Y589764D03*
X165748D03*
Y592913D03*
X165749Y542519D03*
X175197Y592913D03*
X172048D03*
X209842Y555119D03*
Y551969D03*
X181497Y592913D03*
X197244Y545669D03*
X194094Y548820D03*
X209842Y548819D03*
X175197Y548821D03*
X168898Y545669D03*
X156300Y539371D03*
X194094Y545669D03*
X197244Y542520D03*
X194094Y602362D03*
X206692Y596063D03*
X194093D03*
X203605Y605450D03*
X200393Y596063D03*
X187795Y602363D03*
X153149Y605513D03*
X209841Y596063D03*
X190945Y599213D03*
X190944Y596063D03*
X187796Y599212D03*
X184645Y599213D03*
X159448Y596063D03*
X168898D03*
X203542Y602362D03*
Y599213D03*
X206692Y602362D03*
X203542Y596063D03*
X194094Y599213D03*
X162598Y596063D03*
X165748Y599213D03*
X168898D03*
X162598D03*
X159448D03*
X172048Y596063D03*
X178346Y596064D03*
X178347Y599213D03*
X181496Y596062D03*
X209841Y599212D03*
X206692Y599213D03*
X165748Y596063D03*
X175197D03*
Y599213D03*
X172048D03*
X219800Y445700D03*
X213874Y445226D03*
X216141Y580315D03*
X212992Y586614D03*
X216141Y577165D03*
X212991Y567718D03*
X216141Y583465D03*
Y586614D03*
Y564569D03*
X212992Y561417D03*
X216141Y567718D03*
X219293Y567717D03*
X212992Y580315D03*
X212991Y577165D03*
Y574016D03*
X216141D03*
Y561419D03*
X212991Y583465D03*
Y542519D03*
X212992Y589764D03*
Y555119D03*
Y558268D03*
X216142Y548820D03*
X216141Y555120D03*
Y558269D03*
X222441Y548820D03*
X219291D03*
X212992Y551969D03*
X216141Y551970D03*
X212992Y548819D03*
X216141Y589762D03*
X212993Y592912D03*
X212992Y564567D03*
Y545669D03*
X216142D03*
X222440Y605512D03*
X212992Y602363D03*
X212991Y599212D03*
X216141D03*
X762173Y294089D03*
X781088Y294094D03*
X771653Y294093D03*
X777952Y290944D03*
X777989Y294093D03*
X774802Y290944D03*
X774835Y294088D03*
X768503Y290944D03*
X768498Y294124D03*
X765353Y290944D03*
X765325Y294102D03*
X759054Y290944D03*
X759055Y294094D03*
X755905Y290944D03*
Y294093D03*
X787401Y290944D03*
X787408Y294074D03*
X784251Y290944D03*
X784258Y294064D03*
G54D31*
X346457Y66850D03*
X353543Y70787D03*
Y62913D03*
Y55039D03*
X346457Y74724D03*
Y84567D03*
X353543Y86535D03*
Y78661D03*
G54D29*
X305906Y182874D03*
G54D12*
X80708Y44292D03*
X61024Y34449D03*
X33464D03*
X56102Y24606D03*
X38386D03*
X108268Y44292D03*
X103346Y34449D03*
X85630D03*
X590300Y574400D03*
X600300D03*
X610300D03*
G54D18*
X67853Y573865D03*
X91700Y744800D03*
X96500D03*
X101300D03*
X106100D03*
X110900D03*
X115700D03*
X120500D03*
X125300D03*
X200394Y574016D03*
X197245Y555118D03*
X334582Y291284D03*
Y279784D03*
Y330271D03*
Y316574D03*
Y305074D03*
Y366974D03*
Y355474D03*
Y341771D03*
X335000Y615400D03*
X335300Y609800D03*
X335000Y621200D03*
X628160Y569095D03*
X619400Y570451D03*
X721260Y272047D03*
X700546Y577599D03*
X691796D03*
X691296Y572599D03*
X705696D03*
X696296Y577599D03*
X709296Y572599D03*
Y577599D03*
X702096Y572599D03*
X694896D03*
X698496D03*
X704796Y577599D03*
X709569Y582496D03*
X698769D03*
X695169D03*
X691569D03*
X702369D03*
X705969D03*
X777550Y62350D03*
X737009Y237400D03*
X771653Y246887D03*
X798000Y459300D03*
X751100Y405400D03*
X755900D03*
X760700D03*
X765500D03*
X770300D03*
X775100D03*
X790600Y458000D03*
X781000D03*
X785800D03*
X776200D03*
X789500Y405400D03*
X784700D03*
X779900D03*
X828000Y459300D03*
X823200D03*
X832800D03*
X818400D03*
X807600D03*
X802800D03*
X812400D03*
X830100Y501500D03*
X839700D03*
X834900D03*
G54D10*
X8500Y18279D03*
Y28279D03*
Y38279D03*
Y48279D03*
Y58279D03*
Y68279D03*
X13721Y8500D03*
X8500Y13279D03*
Y23279D03*
Y33279D03*
Y43279D03*
Y53279D03*
Y63279D03*
Y78279D03*
Y88279D03*
Y98279D03*
Y108279D03*
Y118279D03*
Y128279D03*
Y73279D03*
Y83279D03*
Y93279D03*
Y103279D03*
Y113279D03*
Y123279D03*
Y133279D03*
Y138279D03*
Y148279D03*
Y158279D03*
Y168279D03*
Y178279D03*
Y188279D03*
Y198279D03*
Y143279D03*
Y153279D03*
Y163279D03*
Y173279D03*
Y183279D03*
Y193279D03*
Y208279D03*
Y218279D03*
Y228279D03*
Y238279D03*
Y248279D03*
Y258279D03*
Y203279D03*
Y213279D03*
Y223279D03*
Y233279D03*
Y243279D03*
Y253279D03*
Y263279D03*
Y268279D03*
Y278279D03*
Y288279D03*
Y298279D03*
Y308279D03*
Y318279D03*
Y328279D03*
Y273279D03*
Y283279D03*
Y293279D03*
Y303279D03*
Y313279D03*
Y323279D03*
Y338279D03*
Y348279D03*
Y358279D03*
Y368279D03*
Y378279D03*
Y388279D03*
Y333279D03*
Y343279D03*
Y353279D03*
Y363279D03*
Y373279D03*
Y383279D03*
Y393279D03*
Y398279D03*
Y408279D03*
Y418279D03*
Y403279D03*
Y413279D03*
Y423279D03*
X8892Y723187D03*
X11090Y727806D03*
X13500Y732400D03*
X78721Y8500D03*
X68721D03*
X58721D03*
X48721D03*
X38721D03*
X28721D03*
X18721D03*
X73721D03*
X53721D03*
X43721D03*
X33721D03*
X23721D03*
X77780Y61790D03*
X73760Y67930D03*
X56960Y58900D03*
X54050Y63260D03*
X43510Y57810D03*
X29890Y54070D03*
X49460Y63690D03*
X68730Y67930D03*
X63721Y8500D03*
X62276Y550493D03*
X64701Y570716D03*
Y564416D03*
X64884Y650984D03*
X75300Y679300D03*
Y674300D03*
X78370Y724300D03*
Y719500D03*
X28100Y755600D03*
X33100D03*
X69057Y755280D03*
X74057D03*
X20300Y746200D03*
X15800Y736900D03*
X18100Y741500D03*
X22600Y750800D03*
X79057Y755280D03*
X108721Y8500D03*
X98721D03*
X88721D03*
X112197Y65406D03*
Y60406D03*
Y55406D03*
X103721Y8500D03*
X93721D03*
X83721D03*
X84610Y64470D03*
X98770Y60860D03*
X112197Y75406D03*
Y85406D03*
Y95406D03*
Y105406D03*
Y115406D03*
Y120406D03*
Y110406D03*
Y100406D03*
Y90406D03*
Y80406D03*
Y70406D03*
Y145406D03*
Y195406D03*
Y185406D03*
Y175406D03*
Y165406D03*
Y155406D03*
Y200406D03*
Y190406D03*
Y180406D03*
Y170406D03*
Y160406D03*
Y150406D03*
Y265406D03*
Y255406D03*
Y245406D03*
Y235406D03*
Y225406D03*
Y215406D03*
Y205406D03*
Y260406D03*
Y250406D03*
Y240406D03*
Y230406D03*
Y220406D03*
Y210406D03*
Y325406D03*
Y315406D03*
Y305406D03*
Y295406D03*
Y285406D03*
Y275406D03*
Y330406D03*
Y320406D03*
Y310406D03*
Y300406D03*
Y290406D03*
Y280406D03*
Y270406D03*
Y390406D03*
Y380406D03*
Y370406D03*
Y360406D03*
Y350406D03*
Y395406D03*
Y385406D03*
Y375406D03*
Y365406D03*
Y355406D03*
Y345406D03*
Y335406D03*
Y340406D03*
Y420406D03*
Y410406D03*
Y400406D03*
Y425406D03*
Y415406D03*
Y405406D03*
X107100Y497300D03*
X138900Y525999D03*
X135012Y510200D03*
X119400Y511500D03*
X133152Y484074D03*
X105350Y511850D03*
X94473Y547093D03*
X89901Y587466D03*
X136990Y535235D03*
X103600Y637800D03*
X103500Y645500D03*
Y650535D03*
X101400Y606300D03*
X97800D03*
X101500Y597000D03*
X85500Y628500D03*
X144800Y657900D03*
X81300Y675100D03*
Y680100D03*
X83170Y724300D03*
Y719500D03*
X87683Y698924D03*
X134057Y755280D03*
X124057D03*
X114057D03*
X104057D03*
X94057D03*
X84057D03*
X89057D03*
X99057D03*
X109057D03*
X119057D03*
X129057D03*
X203307Y506400D03*
X203500Y513500D03*
X207500Y503000D03*
X191418Y509981D03*
X170870Y492270D03*
X158000Y480700D03*
X146143Y481057D03*
X191100Y526000D03*
X156297Y558267D03*
X191200Y529400D03*
X159448Y551968D03*
X166690Y615060D03*
X166600Y617850D03*
X196855Y698355D03*
X208300Y704985D03*
X203500D03*
X198700D03*
X193900D03*
X191766Y679920D03*
X202800Y660900D03*
X189000Y659900D03*
X211700Y513500D03*
X220100Y513400D03*
X211196Y487762D03*
X222600Y503500D03*
X246000Y516670D03*
X264040Y648370D03*
X247725Y656375D03*
X216600Y658400D03*
X266571Y630071D03*
X222700Y704985D03*
X217900D03*
X213100D03*
X261248Y700086D03*
X272050Y711810D03*
X267880Y704920D03*
X262634Y711233D03*
X266400Y675349D03*
X265000Y662574D03*
X247825Y670375D03*
X235100Y679921D03*
X221575Y695400D03*
X242000Y693400D03*
X254648Y745463D03*
X340297Y117548D03*
X341484Y110328D03*
X296282Y189224D03*
Y184424D03*
X301082D03*
Y189224D03*
X307364Y505750D03*
X321976D03*
X329035Y519325D03*
X293793Y521556D03*
X321208Y519411D03*
X327110Y583660D03*
X316680Y583527D03*
X337899Y587874D03*
X310350Y538293D03*
X330860Y551744D03*
X325447Y536109D03*
X290300Y636900D03*
X290500Y640600D03*
X331655Y603405D03*
X339822Y609785D03*
X339847Y620281D03*
X305470Y623734D03*
X278546Y633450D03*
X281900Y640900D03*
X306486Y643750D03*
X306286Y633650D03*
X311186Y638550D03*
X301286Y638650D03*
X311386Y633450D03*
X301386Y633650D03*
X311286Y643750D03*
X301186Y643650D03*
X306300Y638600D03*
X317600Y603300D03*
X322586Y653754D03*
X317786D03*
X312986D03*
X308186D03*
X302459Y599531D03*
X306100Y599500D03*
X306231Y602898D03*
X302180Y603084D03*
X281400Y708200D03*
X281500Y712200D03*
X279400Y686400D03*
X340500Y711750D03*
X334057Y755280D03*
X339057D03*
X380500Y33500D03*
Y30000D03*
X384000D03*
X381173Y49058D03*
X381156Y54116D03*
X375200Y63400D03*
X375300Y72150D03*
X374844Y87900D03*
X375000Y107300D03*
X393206Y77614D03*
X374844Y76700D03*
X362000Y124000D03*
X349072Y193574D03*
X400212Y154732D03*
X400351Y165605D03*
X349072Y189774D03*
X371775Y200577D03*
X348082Y186224D03*
X362197Y222068D03*
X362722Y237674D03*
X369000Y512700D03*
X345497Y527644D03*
X355300Y510100D03*
X353300Y521400D03*
X344700Y509000D03*
X368721Y525271D03*
X371900Y481548D03*
X365800Y498300D03*
X373500Y540305D03*
X393912Y568499D03*
X351600Y540600D03*
X348314Y585614D03*
X385600Y529107D03*
X372600Y576207D03*
X374292Y580300D03*
X355012Y582324D03*
X363008Y547309D03*
X371227Y566830D03*
X342133Y603008D03*
X359258Y596820D03*
X367133Y596067D03*
X382380Y612277D03*
X352400Y626102D03*
X372408Y629626D03*
X384220Y700618D03*
X367600Y696800D03*
X381638Y755280D03*
X384809Y752321D03*
X387045Y747849D03*
X389281Y743376D03*
X391517Y738904D03*
X393753Y734432D03*
X395989Y729960D03*
X398225Y725488D03*
X344057Y755280D03*
X459950Y58000D03*
X490050Y45900D03*
X477400Y69300D03*
X521634Y38901D03*
Y34101D03*
X516834Y38901D03*
Y34101D03*
X526434Y43701D03*
X521634D03*
X516834D03*
X536794Y77373D03*
X531664Y78463D03*
X515915Y80576D03*
X520310Y76700D03*
X552540Y64530D03*
X577100Y78600D03*
X545300Y75600D03*
X568000Y70000D03*
X596077Y369579D03*
X576610Y418416D03*
Y423416D03*
Y428416D03*
Y433416D03*
Y438416D03*
Y443416D03*
Y448416D03*
Y453416D03*
Y458416D03*
Y463416D03*
Y468416D03*
Y473416D03*
Y478416D03*
Y483416D03*
Y488416D03*
Y493416D03*
Y498416D03*
Y503416D03*
Y508416D03*
Y513416D03*
Y518416D03*
Y523416D03*
Y528416D03*
Y533416D03*
Y538416D03*
Y543416D03*
Y548416D03*
Y553416D03*
Y558416D03*
Y563416D03*
Y568416D03*
Y573416D03*
Y578416D03*
Y583416D03*
Y588416D03*
Y593416D03*
Y598416D03*
Y603416D03*
Y608416D03*
Y613416D03*
Y618416D03*
Y623416D03*
Y628416D03*
Y633416D03*
Y638416D03*
Y643416D03*
Y648416D03*
Y653416D03*
Y658416D03*
Y663416D03*
Y668416D03*
Y673416D03*
Y678416D03*
Y683416D03*
Y688416D03*
Y693416D03*
Y698416D03*
Y703416D03*
Y708416D03*
Y713416D03*
Y718416D03*
X577063Y723309D03*
X579299Y727781D03*
X581535Y732253D03*
X583771Y736725D03*
X586007Y741198D03*
X588243Y745670D03*
X590479Y750142D03*
X592715Y754614D03*
X641732Y117323D03*
X632873D03*
X624015D03*
X641732Y102362D03*
X632873D03*
X624015D03*
X641732Y87402D03*
X632873D03*
X624015D03*
X641732Y72441D03*
X632873D03*
X624015D03*
X638470Y164470D03*
X634910Y169360D03*
X644100Y199850D03*
X630000Y169600D03*
X629500Y187500D03*
X666700Y205600D03*
X629400Y217300D03*
X648700Y292900D03*
X612300Y344300D03*
X613480Y333710D03*
X629900Y339300D03*
X610300Y354800D03*
X659300Y373100D03*
X637000Y373856D03*
X610000Y467500D03*
X609000Y473500D03*
Y478500D03*
Y483500D03*
X645200Y521900D03*
X650400Y517600D03*
X656400Y517500D03*
X661500Y517600D03*
X629200Y536040D03*
X629080Y539920D03*
X625500Y536100D03*
X615500Y529800D03*
X616710Y534500D03*
X610200Y555400D03*
X625300Y539900D03*
X653600Y540300D03*
X645300Y655200D03*
Y650400D03*
Y645600D03*
Y640800D03*
X655000Y705000D03*
Y700200D03*
Y695400D03*
Y690600D03*
X645300Y684000D03*
Y679200D03*
Y674400D03*
Y669600D03*
Y664800D03*
Y660000D03*
X655000Y685800D03*
X659722Y755280D03*
X649722D03*
X639722D03*
X634722D03*
X644722D03*
X654722D03*
X664722D03*
X720472Y117323D03*
X711613D03*
X702755D03*
X720472Y102362D03*
X711613D03*
X702755D03*
X720472Y87402D03*
X711613D03*
X702755D03*
X720472Y72441D03*
X711613D03*
X702755D03*
X722150Y174300D03*
X727150Y184550D03*
X722150D03*
X711150Y174300D03*
X716650Y184550D03*
X711150D03*
X705650D03*
X721261Y240551D03*
X721260Y234252D03*
X691600Y207600D03*
X677300Y314900D03*
X681200D03*
X684400Y313400D03*
X688000Y313200D03*
X694675Y323900D03*
X708100Y331410D03*
X708483Y311988D03*
X713283D03*
X731400Y362700D03*
X727000Y353000D03*
X712417Y352800D03*
X699900Y453600D03*
X728874Y470860D03*
X725366Y470722D03*
X696800Y476400D03*
X689100Y507900D03*
X670400Y565500D03*
Y560700D03*
Y555900D03*
Y551100D03*
Y546300D03*
Y541500D03*
Y536700D03*
X703440Y548820D03*
X710459Y554134D03*
X719626Y590829D03*
X722300Y608200D03*
X708600Y608500D03*
X729722Y755280D03*
X719722D03*
X709722D03*
X699722D03*
X689722D03*
X679722D03*
X669722D03*
X674722D03*
X684722D03*
X694722D03*
X704722D03*
X714722D03*
X724722D03*
X734722D03*
X761900Y81700D03*
X772700Y113000D03*
X794650Y86050D03*
X769710Y125150D03*
X766110Y125270D03*
X793957Y113436D03*
X761950Y126450D03*
X773200Y97600D03*
X749600Y199300D03*
X749400Y195600D03*
X753800Y181500D03*
X753400Y185400D03*
X741300Y185700D03*
X749455Y202200D03*
X795026Y374556D03*
X799426Y374456D03*
X738465Y352935D03*
X735484Y429378D03*
Y434178D03*
Y462978D03*
Y458178D03*
Y453378D03*
Y448578D03*
Y443778D03*
Y438978D03*
X740300Y427100D03*
Y431900D03*
Y446300D03*
Y441500D03*
Y436700D03*
X750000Y427100D03*
X754800D03*
X783800Y436000D03*
X779000D03*
X793400D03*
X788600D03*
X788400Y427100D03*
X783600D03*
X778800D03*
X774200Y436000D03*
X774000Y427100D03*
X769200D03*
X764400D03*
X759600D03*
X794700Y505200D03*
X735484Y467778D03*
X797323Y512162D03*
X782000Y505600D03*
X771184Y514916D03*
X753099Y530282D03*
X799722Y755280D03*
X789722D03*
X779722D03*
X769722D03*
X759722D03*
X749722D03*
X739722D03*
X744722D03*
X754722D03*
X764722D03*
X774722D03*
X784722D03*
X794722D03*
X837895Y8500D03*
X847895D03*
X857895D03*
X862895D03*
X852895D03*
X842895D03*
X802227Y208424D03*
X802246Y205826D03*
X804600Y210800D03*
X808400D03*
X810300Y326450D03*
X811600Y317300D03*
X810946Y389734D03*
X811112Y393735D03*
X804300Y436500D03*
X813900D03*
X809100D03*
X818700D03*
X823500D03*
X846000Y476100D03*
X810200Y494900D03*
X815100Y499800D03*
X805200Y499900D03*
X815300Y494700D03*
X805300Y494900D03*
X815200Y505000D03*
X805100Y504900D03*
X810214Y499850D03*
X810400Y505000D03*
X849050Y481050D03*
X809384Y484984D03*
X804584Y526584D03*
X821050Y533350D03*
X849722Y755280D03*
X839722D03*
X829722D03*
X819722D03*
X809722D03*
X804722D03*
X814722D03*
X824722D03*
X834722D03*
X844722D03*
X854722D03*
X867895Y8500D03*
X877895D03*
X887895D03*
X897895D03*
X907895D03*
X916697Y19698D03*
Y29698D03*
Y39698D03*
Y49698D03*
Y59698D03*
Y69698D03*
Y64698D03*
Y54698D03*
Y44698D03*
Y34698D03*
Y24698D03*
Y14698D03*
X912895Y8500D03*
X902895D03*
X892895D03*
X882895D03*
X872895D03*
X916697Y79698D03*
Y89698D03*
Y99698D03*
Y109698D03*
Y119698D03*
Y129698D03*
Y134698D03*
Y124698D03*
Y114698D03*
Y104698D03*
Y94698D03*
Y84698D03*
Y74698D03*
Y139698D03*
Y149698D03*
Y159698D03*
Y169698D03*
Y179698D03*
Y189698D03*
Y199698D03*
Y194698D03*
Y184698D03*
Y174698D03*
Y164698D03*
Y154698D03*
Y144698D03*
Y209698D03*
Y219698D03*
Y229698D03*
Y239698D03*
Y249698D03*
Y259698D03*
Y264698D03*
Y254698D03*
Y244698D03*
Y234698D03*
Y224698D03*
Y214698D03*
Y204698D03*
X888551Y226649D03*
X882871Y243771D03*
X892449Y241249D03*
X886300Y221150D03*
X916697Y269698D03*
Y279698D03*
Y289698D03*
Y299698D03*
Y309698D03*
Y319698D03*
Y329698D03*
Y324698D03*
Y314698D03*
Y304698D03*
Y294698D03*
Y284698D03*
Y274698D03*
X896969Y301500D03*
X916697Y339698D03*
Y349698D03*
Y359698D03*
Y369698D03*
Y379698D03*
Y389698D03*
Y394698D03*
Y384698D03*
Y374698D03*
Y364698D03*
Y354698D03*
Y344698D03*
Y334698D03*
X881147Y394517D03*
X916697Y399698D03*
Y409698D03*
Y419698D03*
Y429698D03*
Y439698D03*
Y449698D03*
Y459698D03*
Y454698D03*
Y444698D03*
Y434698D03*
Y424698D03*
Y414698D03*
Y404698D03*
X880887Y399474D03*
X916697Y469698D03*
Y479698D03*
Y489698D03*
Y499698D03*
Y509698D03*
Y519698D03*
Y524698D03*
Y514698D03*
Y504698D03*
Y494698D03*
Y484698D03*
Y474698D03*
Y464698D03*
Y529698D03*
Y539698D03*
Y549698D03*
Y559698D03*
Y569698D03*
Y579698D03*
Y589698D03*
Y584698D03*
Y574698D03*
Y564698D03*
Y554698D03*
Y544698D03*
Y534698D03*
Y599698D03*
Y609698D03*
Y619698D03*
Y629698D03*
Y639698D03*
Y649698D03*
Y659698D03*
Y654698D03*
Y644698D03*
Y634698D03*
Y624698D03*
Y614698D03*
Y604698D03*
Y594698D03*
Y669698D03*
Y679698D03*
Y689698D03*
Y699698D03*
Y709698D03*
Y719698D03*
Y714698D03*
Y704698D03*
Y694698D03*
Y684698D03*
Y674698D03*
Y664698D03*
X914700Y726100D03*
X912436Y730603D03*
X910200Y735300D03*
X907564Y739747D03*
X905500Y744400D03*
X903192Y748791D03*
X900800Y753700D03*
X894722Y755280D03*
G54D24*
X200394Y570866D03*
G54D35*
X488838Y164744D03*
G54D13*
X18700Y54650D03*
X209189Y37075D03*
Y383483D03*
X489331Y245605D03*
Y698924D03*
X901000Y21400D03*
X902500Y676000D03*
G54D34*
X488838Y137225D03*
G54D16*
X89764Y238386D03*
X309252Y413583D03*
G54D25*
X163189Y669291D03*
G54D37*
X629921Y57874D03*
X708661D03*
G54D39*
X652756Y180000D03*
X865353Y332598D03*
G54D28*
X339331Y91929D03*
X360669Y49803D03*
G54D22*
X90157Y413583D03*
X309055Y157677D03*
G54D15*
X70865Y98425D03*
Y472440D03*
X314960D03*
X405511Y39370D03*
X364173Y740157D03*
X612204Y433070D03*
Y740157D03*
X875984Y433070D03*
Y740157D03*
G54D20*
X49213D03*
X875985Y59055D03*
G54D17*
X71002Y577013D03*
X67852Y586463D03*
Y583313D03*
X132100Y493000D03*
X114070Y481948D03*
X179000Y499800D03*
X175100Y477000D03*
X421653Y126378D03*
X435827D03*
X450000D03*
X464173D03*
X428740Y121654D03*
X442913D03*
X457086D03*
X471260D03*
X421653Y183071D03*
X435827D03*
X450000D03*
X464173D03*
X421653Y140551D03*
X428740Y135827D03*
X435827Y140551D03*
X442913Y135827D03*
X450000Y140551D03*
X457086Y135827D03*
X464173Y140551D03*
X471260Y135827D03*
X421653Y154725D03*
X428740Y150000D03*
X435827Y154725D03*
X442913Y150000D03*
X450000Y154725D03*
X457086Y150000D03*
X464173Y154725D03*
X471260Y150000D03*
X421653Y168898D03*
X428740Y164173D03*
X435827Y168898D03*
X442913Y164173D03*
X450000Y168898D03*
X457086Y164173D03*
X464173Y168898D03*
X471260Y164173D03*
X506693Y126378D03*
X520866D03*
X535039D03*
X513779Y121654D03*
X527953D03*
X506693Y183071D03*
X520866D03*
X535039D03*
X506693Y140551D03*
X513779Y135827D03*
X520866Y140551D03*
X527953Y135827D03*
X535039Y140551D03*
X506693Y154725D03*
X513779Y150000D03*
X520866Y154725D03*
X527953Y150000D03*
X535039Y154725D03*
X506693Y168898D03*
X513779Y164173D03*
X520866Y168898D03*
X527953Y164173D03*
X535039Y168898D03*
X549212Y126378D03*
X542126Y121654D03*
X556299D03*
X549212Y183071D03*
X542126Y135827D03*
X549212Y140551D03*
X556299Y135827D03*
X542126Y150000D03*
X549212Y154725D03*
X556299Y150000D03*
X542126Y164173D03*
X549212Y168898D03*
X556299Y164173D03*
X704579Y258164D03*
X730710Y256302D03*
X733858Y256299D03*
Y253149D03*
X730710Y253152D03*
X733859Y234253D03*
Y237403D03*
X730710D03*
Y234254D03*
X733858Y243700D03*
Y246849D03*
Y249999D03*
Y265747D03*
X730710Y240553D03*
Y243702D03*
Y246852D03*
Y250002D03*
Y265750D03*
X721295Y221651D03*
X718089Y243684D03*
X721260Y253150D03*
Y259449D03*
Y265748D03*
X721261Y246851D03*
X733859Y240552D03*
X727559Y259449D03*
Y265748D03*
Y253150D03*
Y240551D03*
X727560Y246851D03*
X727559Y221654D03*
Y234252D03*
X727594Y227950D03*
X696600Y241500D03*
X701500Y250564D03*
X733859Y275198D03*
X730710Y272048D03*
X733858Y268897D03*
X730710Y268899D03*
X721260Y275196D03*
X727559Y272047D03*
X784253Y227953D03*
Y231103D03*
X752756Y234253D03*
Y231103D03*
Y224804D03*
Y227954D03*
X749606Y231103D03*
Y234253D03*
Y227954D03*
Y224804D03*
X737008Y256299D03*
X740158D03*
Y253149D03*
X737008D03*
X771655Y237402D03*
X737008Y243700D03*
Y246849D03*
Y249999D03*
Y265747D03*
X740158Y246849D03*
Y265747D03*
X740122Y243700D03*
X740158Y249999D03*
X752756Y221654D03*
X737008D03*
X777954Y237402D03*
Y227953D03*
Y231103D03*
X793701Y221654D03*
X781103Y227954D03*
X746457Y224804D03*
X755906D03*
X737009Y227953D03*
Y234253D03*
Y231103D03*
X774804Y221655D03*
Y224804D03*
Y227954D03*
X746457D03*
X755906D03*
X746457Y231103D03*
X755906D03*
X746457Y234253D03*
X755906D03*
X765355D03*
X765354Y231102D03*
X765355Y227953D03*
X740132Y240562D03*
X759055Y221654D03*
X765355Y224804D03*
X771654Y215355D03*
Y209056D03*
Y212205D03*
X765354Y221654D03*
X743307D03*
X762205Y215355D03*
X781103Y237402D03*
Y231103D03*
X787402Y221654D03*
X787401Y215354D03*
X793701Y231103D03*
Y237402D03*
X781102Y221654D03*
X749606D03*
X762205Y212205D03*
X765355Y240552D03*
X743307Y246850D03*
X762217Y240526D03*
X755880Y240563D03*
X749580D03*
X755869Y253149D03*
X762167Y246850D03*
X755907Y246851D03*
X749569Y246850D03*
X762168Y253149D03*
X749608Y253150D03*
X743282Y253161D03*
X755868Y265748D03*
X755882Y259461D03*
X762218Y259425D03*
X749582Y259461D03*
X743282D03*
X762181Y265762D03*
X749582Y265761D03*
X743282D03*
X743281Y240562D03*
X768480Y265762D03*
X768518Y259425D03*
X768467Y253149D03*
Y246850D03*
X740158Y272046D03*
X737008D03*
Y268897D03*
X740158D03*
X737009Y275196D03*
X790526Y300406D03*
X765369Y281474D03*
X771669D03*
X781120Y284665D03*
X759070Y281514D03*
X749816Y303716D03*
X777790Y304778D03*
X769768Y304464D03*
X759208Y304284D03*
X743283Y272060D03*
X755882D03*
X749581D03*
X807468Y234464D03*
G54D19*
X75197Y572437D03*
X67853Y558117D03*
X97926Y502300D03*
X86699D03*
X81094Y502166D03*
X89899Y558115D03*
X86750Y573864D03*
X89899D03*
X86750Y567565D03*
X89899Y564415D03*
X106272Y547370D03*
X93048Y577014D03*
X108371Y577258D03*
X172000Y577150D03*
X165748Y558268D03*
X168898Y589764D03*
Y561417D03*
X156299Y586614D03*
Y580315D03*
X159449Y567717D03*
X165748Y583464D03*
X203542Y586614D03*
Y580315D03*
X178344Y577166D03*
X178346Y586615D03*
X181497Y586614D03*
X178347Y574018D03*
Y570868D03*
X190944Y586614D03*
X203543Y561418D03*
Y564568D03*
X165748Y551968D03*
X178346Y555119D03*
X178347Y564569D03*
X190944Y555118D03*
X181497Y555120D03*
X765353Y237402D03*
X740158Y275197D03*
G54D40*
X769266Y326534D03*
X751566Y327434D03*
X799534Y339466D03*
X760252Y353266D03*
X768384Y345134D03*
X761134Y334666D03*
X772352Y341266D03*
X780484Y333134D03*
X777434Y353566D03*
X785566Y345434D03*
X789334Y341766D03*
X797466Y333634D03*
X743434Y335566D03*
X749534Y346566D03*
X757666Y338434D03*
X807666Y331334D03*
G54D32*
X346457Y57007D03*
%LPC*%
G75*
G54D41*
G01X-13131Y-65072D02*
Y-145072D01*
G01D02*
X1244069D01*
G01X-29131Y-65072D02*
Y-33072D01*
G01X-13131Y-65072D02*
X1244069D01*
G01X-13131Y-100572D02*
X1244069D01*
G01X-17131Y-49072D02*
G02I-12000J0D01*
G01X-22281D02*
G02I-6850J0D01*
G01X-13131D02*
X-45131D01*
G01X456569Y-65072D02*
Y-145072D01*
G01X594069Y-65072D02*
Y-145072D01*
G01X709069Y-65072D02*
Y-145072D01*
G01X876569Y-65072D02*
Y-145072D01*
G01X1046569Y-65072D02*
Y-145072D01*
G01X1244069Y-65072D02*
Y-145072D01*
G01X1272069Y-49072D02*
G02I-12000J0D01*
G01X1266919D02*
G02I-6850J0D01*
G01X1276069D02*
X1244069D01*
G01X1260069Y-65072D02*
Y-33072D01*
G54D42*
G01X13215Y-125739D02*
X14089Y-124864D01*
X14744Y-123406D01*
X15181Y-121363D01*
X14744Y-119614D01*
X13871Y-118447D01*
X12342Y-117572D01*
X6447D01*
Y-135072D01*
X13652D01*
X15181Y-133906D01*
X16054Y-132155D01*
X16491Y-130114D01*
X16054Y-128072D01*
X14744Y-126322D01*
X13215Y-125739D01*
X6447D01*
G01X25912Y-135072D02*
Y-123406D01*
G01Y-125739D02*
X27004Y-124572D01*
X28096Y-123697D01*
X29624Y-123406D01*
X30715Y-123697D01*
X32026Y-124572D01*
G01X41884Y-140322D02*
X43194Y-140905D01*
X44941Y-140322D01*
X46032Y-139156D01*
X46906Y-137697D01*
X48215Y-133031D01*
X51054Y-123406D01*
G01X44067D02*
X48215Y-133031D01*
G01X67462Y-124864D02*
X65934Y-123697D01*
X64624Y-123406D01*
X62877Y-123989D01*
X61567Y-125155D01*
X60694Y-127197D01*
X60475Y-129239D01*
X60694Y-131281D01*
X61567Y-133031D01*
X62877Y-134489D01*
X64624Y-135072D01*
X66152Y-134489D01*
X67462Y-133322D01*
G01X78194Y-127197D02*
X85181D01*
X84526Y-125155D01*
X83434Y-123989D01*
X81906Y-123406D01*
X80377Y-123697D01*
X79067Y-124572D01*
X78194Y-126614D01*
X77757Y-128364D01*
Y-130114D01*
X78194Y-131864D01*
X79286Y-133614D01*
X80596Y-134780D01*
X82124Y-135072D01*
X83652Y-134489D01*
X85181Y-132739D01*
G01X121272Y-119031D02*
X119962Y-118155D01*
X118434Y-117572D01*
X116687D01*
X114722Y-118447D01*
X113194Y-119905D01*
X112102Y-121656D01*
X111229Y-124572D01*
X111010Y-127197D01*
X111447Y-129822D01*
X112102Y-131572D01*
X113412Y-133322D01*
X114941Y-134489D01*
X116469Y-135072D01*
X117997D01*
X119526Y-134489D01*
X120836Y-133614D01*
X121928Y-132448D01*
G01X137899Y-135072D02*
Y-123406D01*
G01Y-125447D02*
X137026Y-124281D01*
X135715Y-123697D01*
X134187Y-123406D01*
X132659Y-123989D01*
X131349Y-125155D01*
X130475Y-126905D01*
X130039Y-129239D01*
X130475Y-131572D01*
X131349Y-133322D01*
X132659Y-134489D01*
X134187Y-135072D01*
X135715Y-134780D01*
X137026Y-133906D01*
X137899Y-132739D01*
G01X147757Y-135072D02*
Y-123406D01*
G01Y-126322D02*
X148631Y-124864D01*
X149941Y-123697D01*
X151687Y-123406D01*
X153215Y-123697D01*
X154526Y-124864D01*
X155181Y-126905D01*
Y-135072D01*
G01X164384Y-140322D02*
X165694Y-140905D01*
X167441Y-140322D01*
X168532Y-139156D01*
X169406Y-137697D01*
X170715Y-133031D01*
X173554Y-123406D01*
G01X166567D02*
X170715Y-133031D01*
G01X186469Y-135072D02*
X185159Y-134780D01*
X183849Y-133614D01*
X182975Y-131572D01*
X182539Y-129239D01*
X182975Y-126905D01*
X183849Y-124864D01*
X185159Y-123697D01*
X186469Y-123406D01*
X187779Y-123697D01*
X189089Y-124864D01*
X189962Y-126905D01*
X190181Y-129239D01*
X189962Y-131572D01*
X189089Y-133614D01*
X187779Y-134780D01*
X186469Y-135072D01*
G01X200257D02*
Y-123406D01*
G01Y-126322D02*
X201131Y-124864D01*
X202441Y-123697D01*
X204187Y-123406D01*
X205715Y-123697D01*
X207026Y-124864D01*
X207681Y-126905D01*
Y-135072D01*
G01X236349Y-117572D02*
X241589D01*
G01X238969D02*
Y-135072D01*
G01X236349D02*
X241589D01*
G01X256469D02*
X254722Y-134780D01*
X253194Y-133614D01*
X251884Y-131864D01*
X251010Y-129822D01*
X250574Y-127489D01*
Y-125155D01*
X251010Y-122822D01*
X251884Y-120780D01*
X253194Y-119031D01*
X254722Y-117864D01*
X256469Y-117572D01*
X258215Y-117864D01*
X259744Y-119031D01*
X261054Y-120780D01*
X261928Y-122822D01*
X262364Y-125155D01*
Y-127489D01*
X261928Y-129822D01*
X261054Y-131864D01*
X259744Y-133614D01*
X258215Y-134780D01*
X256469Y-135072D01*
G01X268292D02*
Y-117572D01*
X273969Y-132155D01*
X279646Y-117572D01*
Y-135072D01*
G01X307877Y-140905D02*
X305694Y-137989D01*
X304602Y-135072D01*
Y-123406D01*
X305694Y-120489D01*
X307877Y-117572D01*
G01X321010Y-123406D02*
X323631Y-135072D01*
X326469Y-123406D01*
X329307Y-135072D01*
X331928Y-123406D01*
G01X340039Y-135655D02*
X347899Y-117572D01*
G01X376349D02*
X381589D01*
G01X378969D02*
Y-135072D01*
G01X376349D02*
X381589D01*
G01X396469D02*
X394722Y-134780D01*
X393194Y-133614D01*
X391884Y-131864D01*
X391010Y-129822D01*
X390574Y-127489D01*
Y-125155D01*
X391010Y-122822D01*
X391884Y-120780D01*
X393194Y-119031D01*
X394722Y-117864D01*
X396469Y-117572D01*
X398215Y-117864D01*
X399744Y-119031D01*
X401054Y-120780D01*
X401928Y-122822D01*
X402364Y-125155D01*
Y-127489D01*
X401928Y-129822D01*
X401054Y-131864D01*
X399744Y-133614D01*
X398215Y-134780D01*
X396469Y-135072D01*
G01X418772Y-119031D02*
X417462Y-118155D01*
X415934Y-117572D01*
X414187D01*
X412222Y-118447D01*
X410694Y-119905D01*
X409602Y-121656D01*
X408729Y-124572D01*
X408510Y-127197D01*
X408947Y-129822D01*
X409602Y-131572D01*
X410912Y-133322D01*
X412441Y-134489D01*
X413969Y-135072D01*
X415497D01*
X417026Y-134489D01*
X418336Y-133614D01*
X419428Y-132448D01*
G01X432561Y-140905D02*
X434744Y-137989D01*
X435836Y-135072D01*
Y-123406D01*
X434744Y-120489D01*
X432561Y-117572D01*
G01X180792Y-90072D02*
Y-72572D01*
X186469Y-87155D01*
X192146Y-72572D01*
Y-90072D01*
G01X203969D02*
X202659Y-89780D01*
X201349Y-88614D01*
X200475Y-86572D01*
X200039Y-84239D01*
X200475Y-81905D01*
X201349Y-79864D01*
X202659Y-78697D01*
X203969Y-78406D01*
X205279Y-78697D01*
X206589Y-79864D01*
X207462Y-81905D01*
X207681Y-84239D01*
X207462Y-86572D01*
X206589Y-88614D01*
X205279Y-89780D01*
X203969Y-90072D01*
G01X225399Y-72572D02*
Y-90072D01*
G01Y-87448D02*
X224526Y-88906D01*
X223215Y-89780D01*
X221687Y-90072D01*
X219941Y-89489D01*
X218631Y-88031D01*
X217757Y-86281D01*
X217539Y-84239D01*
X217757Y-82197D01*
X218631Y-80447D01*
X219941Y-78989D01*
X221687Y-78406D01*
X223215Y-78697D01*
X224307Y-79281D01*
X225399Y-80447D01*
G01X235694Y-82197D02*
X242681D01*
X242026Y-80155D01*
X240934Y-78989D01*
X239406Y-78406D01*
X237877Y-78697D01*
X236567Y-79572D01*
X235694Y-81614D01*
X235257Y-83364D01*
Y-85114D01*
X235694Y-86864D01*
X236786Y-88614D01*
X238096Y-89780D01*
X239624Y-90072D01*
X241152Y-89489D01*
X242681Y-87739D01*
G01X256469Y-90072D02*
Y-72572D01*
G01X490269Y-135072D02*
Y-117572D01*
X487649Y-121072D01*
G01Y-135072D02*
X492889D01*
G01X503621Y-127781D02*
X505149Y-125739D01*
X506459Y-124572D01*
X508206Y-123989D01*
X509734Y-124572D01*
X510826Y-125739D01*
X511699Y-127489D01*
X511917Y-129530D01*
X511699Y-131281D01*
X510826Y-133031D01*
X509515Y-134489D01*
X507987Y-135072D01*
X506241Y-134489D01*
X504712Y-132739D01*
X503839Y-130114D01*
X503621Y-127197D01*
X504057Y-123406D01*
X504712Y-121363D01*
X505804Y-119322D01*
X507332Y-117864D01*
X508861Y-117572D01*
X510389Y-118155D01*
X511481Y-119614D01*
G01X520466Y-131572D02*
X521775Y-133614D01*
X523522Y-134780D01*
X525487Y-135072D01*
X527234Y-134780D01*
X528981Y-133322D01*
X530072Y-131572D01*
X530291Y-129822D01*
X529854Y-127781D01*
X528326Y-126322D01*
X526797Y-125739D01*
X524832D01*
G01X526797D02*
X528107Y-124864D01*
X529199Y-123406D01*
X529636Y-121656D01*
X529199Y-119905D01*
X528107Y-118447D01*
X526142Y-117572D01*
X524177Y-117864D01*
X522212Y-119031D01*
G01X542769Y-135072D02*
Y-117572D01*
X540149Y-121072D01*
G01Y-135072D02*
X545389D01*
G01X560269D02*
X561797Y-134780D01*
X563544Y-133906D01*
X564636Y-132448D01*
X565072Y-130405D01*
X564636Y-128364D01*
X563326Y-126614D01*
X561361Y-125739D01*
X559177D01*
X557867Y-125155D01*
X556775Y-123697D01*
X556339Y-121656D01*
X556994Y-119614D01*
X558522Y-118155D01*
X560269Y-117572D01*
X562015Y-118155D01*
X563544Y-119614D01*
X564199Y-121656D01*
X563762Y-123697D01*
X562671Y-125155D01*
X561361Y-125739D01*
X559177D01*
X557212Y-126614D01*
X555902Y-128364D01*
X555466Y-130405D01*
X555902Y-132448D01*
X556994Y-133906D01*
X558741Y-134780D01*
X560269Y-135072D01*
G01X477152Y-90072D02*
Y-72572D01*
X482392D01*
X484139Y-73447D01*
X485449Y-75489D01*
X485886Y-77822D01*
X485449Y-80155D01*
X484357Y-81905D01*
X482392Y-82781D01*
X477152D01*
G01X503822Y-74031D02*
X502512Y-73155D01*
X500984Y-72572D01*
X499237D01*
X497272Y-73447D01*
X495744Y-74905D01*
X494652Y-76656D01*
X493779Y-79572D01*
X493560Y-82197D01*
X493997Y-84822D01*
X494652Y-86572D01*
X495962Y-88322D01*
X497491Y-89489D01*
X499019Y-90072D01*
X500547D01*
X502076Y-89489D01*
X503386Y-88614D01*
X504478Y-87448D01*
G01X518265Y-80739D02*
X519139Y-79864D01*
X519794Y-78406D01*
X520231Y-76363D01*
X519794Y-74614D01*
X518921Y-73447D01*
X517392Y-72572D01*
X511497D01*
Y-90072D01*
X518702D01*
X520231Y-88906D01*
X521104Y-87155D01*
X521541Y-85114D01*
X521104Y-83072D01*
X519794Y-81322D01*
X518265Y-80739D01*
X511497D01*
G01X527469Y-95905D02*
X540569D01*
G01X546497Y-90072D02*
Y-72572D01*
X556541Y-90072D01*
Y-72572D01*
G01X569019Y-90072D02*
X567272Y-89780D01*
X565744Y-88614D01*
X564434Y-86864D01*
X563560Y-84822D01*
X563124Y-82489D01*
Y-80155D01*
X563560Y-77822D01*
X564434Y-75780D01*
X565744Y-74031D01*
X567272Y-72864D01*
X569019Y-72572D01*
X570765Y-72864D01*
X572294Y-74031D01*
X573604Y-75780D01*
X574478Y-77822D01*
X574914Y-80155D01*
Y-82489D01*
X574478Y-84822D01*
X573604Y-86864D01*
X572294Y-88614D01*
X570765Y-89780D01*
X569019Y-90072D01*
G01X647421Y-120489D02*
X648731Y-118739D01*
X650259Y-117864D01*
X652006Y-117572D01*
X654189Y-118155D01*
X655717Y-119614D01*
X656154Y-121363D01*
X655936Y-123114D01*
X655062Y-124572D01*
X650696Y-127489D01*
X648731Y-129530D01*
X647421Y-132448D01*
X646984Y-135072D01*
X656154D01*
G01X619860Y-72572D02*
X625319Y-90072D01*
X630778Y-72572D01*
G01X647186Y-90072D02*
X638452D01*
Y-72572D01*
X647186D01*
G01X643692Y-81030D02*
X638452D01*
G01X655952Y-90072D02*
Y-72572D01*
X661411D01*
X663157Y-73447D01*
X664249Y-74614D01*
X664686Y-76947D01*
X664249Y-79281D01*
X662939Y-80739D01*
X661411Y-81614D01*
X655952D01*
G01X661411D02*
X664686Y-90072D01*
G01X677819Y-90655D02*
X677382Y-90364D01*
Y-89780D01*
X677819Y-89489D01*
X678256Y-89780D01*
Y-90364D01*
X677819Y-90655D01*
G01X832136Y-117572D02*
Y-135072D01*
X823402D01*
G01X815072Y-132448D02*
X813763Y-133906D01*
X812234Y-134780D01*
X810269Y-135072D01*
X808304Y-134489D01*
X806776Y-133322D01*
X805684Y-131281D01*
X805466Y-128947D01*
X805902Y-126614D01*
X806994Y-125155D01*
X808523Y-123989D01*
X810051Y-123697D01*
X811579Y-123989D01*
X813544Y-125155D01*
X812889Y-117572D01*
X806994D01*
G01X798228D02*
X792769Y-135072D01*
X787310Y-117572D01*
G01X770466Y-119031D02*
X771776Y-118155D01*
X773304Y-117572D01*
X775051D01*
X777016Y-118447D01*
X778544Y-119905D01*
X779636Y-121656D01*
X780509Y-124572D01*
X780728Y-127197D01*
X780291Y-129822D01*
X779636Y-131572D01*
X778326Y-133322D01*
X776797Y-134489D01*
X775269Y-135072D01*
X773741D01*
X772212Y-134489D01*
X770902Y-133614D01*
X769810Y-132448D01*
G01X752966Y-119031D02*
X754276Y-118155D01*
X755804Y-117572D01*
X757551D01*
X759516Y-118447D01*
X761044Y-119905D01*
X762136Y-121656D01*
X763009Y-124572D01*
X763228Y-127197D01*
X762791Y-129822D01*
X762136Y-131572D01*
X760826Y-133322D01*
X759297Y-134489D01*
X757769Y-135072D01*
X756241D01*
X754712Y-134489D01*
X753402Y-133614D01*
X752310Y-132448D01*
G01X753402Y-72572D02*
Y-90072D01*
X762136D01*
G01X779199D02*
Y-78406D01*
G01Y-80447D02*
X778326Y-79281D01*
X777015Y-78697D01*
X775487Y-78406D01*
X773959Y-78989D01*
X772649Y-80155D01*
X771775Y-81905D01*
X771339Y-84239D01*
X771775Y-86572D01*
X772649Y-88322D01*
X773959Y-89489D01*
X775487Y-90072D01*
X777015Y-89780D01*
X778326Y-88906D01*
X779199Y-87739D01*
G01X788184Y-95322D02*
X789494Y-95905D01*
X791241Y-95322D01*
X792332Y-94156D01*
X793206Y-92697D01*
X794515Y-88031D01*
X797354Y-78406D01*
G01X790367D02*
X794515Y-88031D01*
G01X806994Y-82197D02*
X813981D01*
X813326Y-80155D01*
X812234Y-78989D01*
X810706Y-78406D01*
X809177Y-78697D01*
X807867Y-79572D01*
X806994Y-81614D01*
X806557Y-83364D01*
Y-85114D01*
X806994Y-86864D01*
X808086Y-88614D01*
X809396Y-89780D01*
X810924Y-90072D01*
X812452Y-89489D01*
X813981Y-87739D01*
G01X824712Y-90072D02*
Y-78406D01*
G01Y-80739D02*
X825804Y-79572D01*
X826896Y-78697D01*
X828424Y-78406D01*
X829515Y-78697D01*
X830826Y-79572D01*
G01X917819Y-135072D02*
X916072Y-134780D01*
X914544Y-133614D01*
X913234Y-131864D01*
X912360Y-129822D01*
X911924Y-127489D01*
Y-125155D01*
X912360Y-122822D01*
X913234Y-120780D01*
X914544Y-119031D01*
X916072Y-117864D01*
X917819Y-117572D01*
X919565Y-117864D01*
X921094Y-119031D01*
X922404Y-120780D01*
X923278Y-122822D01*
X923714Y-125155D01*
Y-127489D01*
X923278Y-129822D01*
X922404Y-131864D01*
X921094Y-133614D01*
X919565Y-134780D01*
X917819Y-135072D01*
G01X919565Y-130405D02*
X922186Y-135072D01*
G01X930516Y-117572D02*
Y-130114D01*
X931389Y-132739D01*
X933136Y-134489D01*
X935319Y-135072D01*
X937502Y-134489D01*
X939249Y-132739D01*
X940122Y-130114D01*
Y-117572D01*
G01X950199D02*
X955439D01*
G01X952819D02*
Y-135072D01*
G01X950199D02*
X955439D01*
G01X965297D02*
Y-117572D01*
X975341Y-135072D01*
Y-117572D01*
G01X992622Y-119031D02*
X991312Y-118155D01*
X989784Y-117572D01*
X988037D01*
X986072Y-118447D01*
X984544Y-119905D01*
X983452Y-121656D01*
X982579Y-124572D01*
X982360Y-127197D01*
X982797Y-129822D01*
X983452Y-131572D01*
X984762Y-133322D01*
X986291Y-134489D01*
X987819Y-135072D01*
X989347D01*
X990876Y-134489D01*
X992186Y-133614D01*
X993278Y-132448D01*
G01X1005319Y-135072D02*
Y-127197D01*
X1000952Y-117572D01*
G01X1009686D02*
X1005319Y-127197D01*
G01X895516Y-90072D02*
Y-72572D01*
X899882D01*
X901629Y-73447D01*
X902939Y-74614D01*
X904031Y-76363D01*
X904904Y-78406D01*
X905122Y-81322D01*
X904904Y-84239D01*
X904031Y-86281D01*
X902939Y-88031D01*
X901629Y-89197D01*
X899882Y-90072D01*
X895516D01*
G01X914544Y-82197D02*
X921531D01*
X920876Y-80155D01*
X919784Y-78989D01*
X918256Y-78406D01*
X916727Y-78697D01*
X915417Y-79572D01*
X914544Y-81614D01*
X914107Y-83364D01*
Y-85114D01*
X914544Y-86864D01*
X915636Y-88614D01*
X916946Y-89780D01*
X918474Y-90072D01*
X920002Y-89489D01*
X921531Y-87739D01*
G01X932044Y-88031D02*
X933136Y-89197D01*
X934664Y-90072D01*
X935974D01*
X937284Y-89489D01*
X938157Y-88614D01*
X938594Y-87448D01*
X938376Y-85697D01*
X937502Y-84822D01*
X933572Y-83072D01*
X932699Y-81030D01*
X933136Y-79572D01*
X934009Y-78697D01*
X935319Y-78406D01*
X936629Y-78697D01*
X937939Y-79572D01*
G01X952819Y-78406D02*
Y-90072D01*
G01Y-73739D02*
X952382Y-73447D01*
Y-72864D01*
X952819Y-72572D01*
X953256Y-72864D01*
Y-73447D01*
X952819Y-73739D01*
G01X967262Y-94447D02*
X968791Y-95614D01*
X970537Y-95905D01*
X972065Y-95614D01*
X973376Y-94156D01*
X974249Y-92114D01*
Y-78406D01*
G01Y-80739D02*
X973376Y-79572D01*
X972065Y-78697D01*
X970537Y-78406D01*
X968791Y-78989D01*
X967699Y-80155D01*
X966825Y-82197D01*
X966389Y-84239D01*
X966607Y-85989D01*
X967481Y-88031D01*
X968791Y-89489D01*
X970537Y-90072D01*
X971847Y-89780D01*
X973376Y-88614D01*
X974249Y-87448D01*
G01X984107Y-90072D02*
Y-78406D01*
G01Y-81322D02*
X984981Y-79864D01*
X986291Y-78697D01*
X988037Y-78406D01*
X989565Y-78697D01*
X990876Y-79864D01*
X991531Y-81905D01*
Y-90072D01*
G01X1002044Y-82197D02*
X1009031D01*
X1008376Y-80155D01*
X1007284Y-78989D01*
X1005756Y-78406D01*
X1004227Y-78697D01*
X1002917Y-79572D01*
X1002044Y-81614D01*
X1001607Y-83364D01*
Y-85114D01*
X1002044Y-86864D01*
X1003136Y-88614D01*
X1004446Y-89780D01*
X1005974Y-90072D01*
X1007502Y-89489D01*
X1009031Y-87739D01*
G01X1019762Y-90072D02*
Y-78406D01*
G01Y-80739D02*
X1020854Y-79572D01*
X1021946Y-78697D01*
X1023474Y-78406D01*
X1024565Y-78697D01*
X1025876Y-79572D01*
G01X1066519Y-117572D02*
X1064772Y-118155D01*
X1063462Y-119614D01*
X1062589Y-121363D01*
X1061934Y-123697D01*
X1061716Y-126322D01*
X1061934Y-128947D01*
X1062589Y-131281D01*
X1063462Y-133031D01*
X1064772Y-134489D01*
X1066519Y-135072D01*
X1068265Y-134489D01*
X1069576Y-133031D01*
X1070449Y-131281D01*
X1071104Y-128947D01*
X1071322Y-126322D01*
X1071104Y-123697D01*
X1070449Y-121363D01*
X1069576Y-119614D01*
X1068265Y-118155D01*
X1066519Y-117572D01*
G01X1084019Y-135072D02*
X1085547Y-134780D01*
X1087294Y-133906D01*
X1088386Y-132448D01*
X1088822Y-130405D01*
X1088386Y-128364D01*
X1087076Y-126614D01*
X1085111Y-125739D01*
X1082927D01*
X1081617Y-125155D01*
X1080525Y-123697D01*
X1080089Y-121656D01*
X1080744Y-119614D01*
X1082272Y-118155D01*
X1084019Y-117572D01*
X1085765Y-118155D01*
X1087294Y-119614D01*
X1087949Y-121656D01*
X1087512Y-123697D01*
X1086421Y-125155D01*
X1085111Y-125739D01*
X1082927D01*
X1080962Y-126614D01*
X1079652Y-128364D01*
X1079216Y-130405D01*
X1079652Y-132448D01*
X1080744Y-133906D01*
X1082491Y-134780D01*
X1084019Y-135072D01*
G01X1097589Y-135655D02*
X1105449Y-117572D01*
G01X1119019D02*
X1117272Y-118155D01*
X1115962Y-119614D01*
X1115089Y-121363D01*
X1114434Y-123697D01*
X1114216Y-126322D01*
X1114434Y-128947D01*
X1115089Y-131281D01*
X1115962Y-133031D01*
X1117272Y-134489D01*
X1119019Y-135072D01*
X1120765Y-134489D01*
X1122076Y-133031D01*
X1122949Y-131281D01*
X1123604Y-128947D01*
X1123822Y-126322D01*
X1123604Y-123697D01*
X1122949Y-121363D01*
X1122076Y-119614D01*
X1120765Y-118155D01*
X1119019Y-117572D01*
G01X1136082Y-135072D02*
X1136519Y-131281D01*
X1137174Y-128072D01*
X1138047Y-125155D01*
X1139139Y-121947D01*
X1140886Y-117572D01*
X1132152D01*
G01X1150089Y-135655D02*
X1157949Y-117572D01*
G01X1167371Y-120489D02*
X1168681Y-118739D01*
X1170209Y-117864D01*
X1171956Y-117572D01*
X1174139Y-118155D01*
X1175667Y-119614D01*
X1176104Y-121363D01*
X1175886Y-123114D01*
X1175012Y-124572D01*
X1170646Y-127489D01*
X1168681Y-129530D01*
X1167371Y-132448D01*
X1166934Y-135072D01*
X1176104D01*
G01X1189019Y-117572D02*
X1187272Y-118155D01*
X1185962Y-119614D01*
X1185089Y-121363D01*
X1184434Y-123697D01*
X1184216Y-126322D01*
X1184434Y-128947D01*
X1185089Y-131281D01*
X1185962Y-133031D01*
X1187272Y-134489D01*
X1189019Y-135072D01*
X1190765Y-134489D01*
X1192076Y-133031D01*
X1192949Y-131281D01*
X1193604Y-128947D01*
X1193822Y-126322D01*
X1193604Y-123697D01*
X1192949Y-121363D01*
X1192076Y-119614D01*
X1190765Y-118155D01*
X1189019Y-117572D01*
G01X1206519Y-135072D02*
Y-117572D01*
X1203899Y-121072D01*
G01Y-135072D02*
X1209139D01*
G01X1223582D02*
X1224019Y-131281D01*
X1224674Y-128072D01*
X1225547Y-125155D01*
X1226639Y-121947D01*
X1228386Y-117572D01*
X1219652D01*
G01X1114216Y-90072D02*
Y-72572D01*
X1118582D01*
X1120329Y-73447D01*
X1121639Y-74614D01*
X1122731Y-76363D01*
X1123604Y-78406D01*
X1123822Y-81322D01*
X1123604Y-84239D01*
X1122731Y-86281D01*
X1121639Y-88031D01*
X1120329Y-89197D01*
X1118582Y-90072D01*
X1114216D01*
G01X1140449D02*
Y-78406D01*
G01Y-80447D02*
X1139576Y-79281D01*
X1138265Y-78697D01*
X1136737Y-78406D01*
X1135209Y-78989D01*
X1133899Y-80155D01*
X1133025Y-81905D01*
X1132589Y-84239D01*
X1133025Y-86572D01*
X1133899Y-88322D01*
X1135209Y-89489D01*
X1136737Y-90072D01*
X1138265Y-89780D01*
X1139576Y-88906D01*
X1140449Y-87739D01*
G01X1154019Y-72572D02*
Y-90072D01*
G01X1150962Y-78406D02*
X1157076D01*
G01X1168244Y-82197D02*
X1175231D01*
X1174576Y-80155D01*
X1173484Y-78989D01*
X1171956Y-78406D01*
X1170427Y-78697D01*
X1169117Y-79572D01*
X1168244Y-81614D01*
X1167807Y-83364D01*
Y-85114D01*
X1168244Y-86864D01*
X1169336Y-88614D01*
X1170646Y-89780D01*
X1172174Y-90072D01*
X1173702Y-89489D01*
X1175231Y-87739D01*
M02*
